(kicad_pcb
	(version 20241229)
	(generator "pcbnew")
	(generator_version "9.0")
	(general
		(thickness 1.59)
		(legacy_teardrops no)
	)
	(paper "A3")
	(title_block
		(title "usb-c-power-adapter")
		(date "2025-06-24")
		(rev "1.1.2")
		(company "Antmicro")
	)
	(layers
		(0 "F.Cu" signal)
		(4 "In1.Cu" signal)
		(6 "In2.Cu" signal)
		(2 "B.Cu" signal)
		(9 "F.Adhes" user "F.Adhesive")
		(11 "B.Adhes" user "B.Adhesive")
		(13 "F.Paste" user)
		(15 "B.Paste" user)
		(5 "F.SilkS" user "F.Silkscreen")
		(7 "B.SilkS" user "B.Silkscreen")
		(1 "F.Mask" user)
		(3 "B.Mask" user)
		(17 "Dwgs.User" user "User.Drawings")
		(19 "Cmts.User" user "User.Comments")
		(21 "Eco1.User" user "User.Eco1")
		(23 "Eco2.User" user "User.Eco2")
		(25 "Edge.Cuts" user)
		(27 "Margin" user)
		(31 "F.CrtYd" user "F.Courtyard")
		(29 "B.CrtYd" user "B.Courtyard")
		(35 "F.Fab" user)
		(33 "B.Fab" user)
	)
	(setup
		(stackup
			(layer "F.SilkS"
				(type "Top Silk Screen")
				(color "White")
			)
			(layer "F.Paste"
				(type "Top Solder Paste")
			)
			(layer "F.Mask"
				(type "Top Solder Mask")
				(color "Black")
				(thickness 0.01)
			)
			(layer "F.Cu"
				(type "copper")
				(thickness 0.035)
			)
			(layer "dielectric 1"
				(type "prepreg")
				(color "FR4 natural")
				(thickness 0.18)
				(material "PR7628")
				(epsilon_r 4.5)
				(loss_tangent 0.02) addsublayer
				(thickness 0.18)
			)
			(layer "In1.Cu"
				(type "copper")
				(thickness 0.035)
			)
			(layer "dielectric 2"
				(type "core")
				(color "FR4 natural")
				(thickness 0.71)
				(material "FR4")
				(epsilon_r 4.5)
				(loss_tangent 0.02)
			)
			(layer "In2.Cu"
				(type "copper")
				(thickness 0.035)
			)
			(layer "dielectric 3"
				(type "prepreg")
				(color "FR4 natural")
				(thickness 0.18)
				(material "FR4PR7628")
				(epsilon_r 4.5)
				(loss_tangent 0.02) addsublayer
				(thickness 0.18)
			)
			(layer "B.Cu"
				(type "copper")
				(thickness 0.035)
			)
			(layer "B.Mask"
				(type "Bottom Solder Mask")
				(color "Black")
				(thickness 0.01)
			)
			(layer "B.Paste"
				(type "Bottom Solder Paste")
			)
			(layer "B.SilkS"
				(type "Bottom Silk Screen")
				(color "White")
			)
			(copper_finish "None")
			(dielectric_constraints no)
		)
		(pad_to_mask_clearance 0)
		(allow_soldermask_bridges_in_footprints no)
		(tenting front back)
		(aux_axis_origin 81.526 111.05)
		(pcbplotparams
			(layerselection 0x00000000_00000000_55555555_5755f5ff)
			(plot_on_all_layers_selection 0x00000000_00000000_00000000_00000000)
			(disableapertmacros no)
			(usegerberextensions no)
			(usegerberattributes yes)
			(usegerberadvancedattributes yes)
			(creategerberjobfile yes)
			(dashed_line_dash_ratio 12.000000)
			(dashed_line_gap_ratio 3.000000)
			(svgprecision 4)
			(plotframeref no)
			(mode 1)
			(useauxorigin no)
			(hpglpennumber 1)
			(hpglpenspeed 20)
			(hpglpendiameter 15.000000)
			(pdf_front_fp_property_popups yes)
			(pdf_back_fp_property_popups yes)
			(pdf_metadata yes)
			(pdf_single_document no)
			(dxfpolygonmode yes)
			(dxfimperialunits yes)
			(dxfusepcbnewfont yes)
			(psnegative no)
			(psa4output no)
			(plot_black_and_white yes)
			(sketchpadsonfab no)
			(plotpadnumbers no)
			(hidednponfab no)
			(sketchdnponfab yes)
			(crossoutdnponfab yes)
			(subtractmaskfromsilk no)
			(outputformat 1)
			(mirror no)
			(drillshape 1)
			(scaleselection 1)
			(outputdirectory "")
		)
	)
	(net 0 "")
	(net 1 "+3V3")
	(net 2 "GND")
	(net 3 "VCC")
	(net 4 "Net-(C13-Pad1)")
	(net 5 "+12V")
	(net 6 "VBUS")
	(net 7 "Net-(Q1-G)")
	(net 8 "Net-(L1-Pad1)")
	(net 9 "Net-(U4-EN)")
	(net 10 "/DC-DC Converters/VDD_12V_DCDC")
	(net 11 "/DC-DC Converters/VDRV_12V_DCDC")
	(net 12 "Net-(U2-V_{CIN})")
	(net 13 "/DC-DC Converters/12V_SS")
	(net 14 "Net-(U1-VREG_2V7)")
	(net 15 "Net-(U1-VREG_1V2)")
	(net 16 "Net-(C10-Pad1)")
	(net 17 "Net-(U2-BOOT)")
	(net 18 "Net-(U2-V_{SNS})")
	(net 19 "/DC-DC Converters/12V_SNS")
	(net 20 "Net-(C19-Pad1)")
	(net 21 "Net-(U3-SW)")
	(net 22 "Net-(U3-BST)")
	(net 23 "Net-(U4-SW)")
	(net 24 "Net-(U4-BST)")
	(net 25 "+5V")
	(net 26 "Net-(D5-C)")
	(net 27 "POWER_OK2")
	(net 28 "POWER_OK3")
	(net 29 "/USB PD/CC1")
	(net 30 "unconnected-(J1-D_{A}+-PadA6)")
	(net 31 "unconnected-(J1-D_{A}--PadA7)")
	(net 32 "unconnected-(J1-SBU_{1}-PadA8)")
	(net 33 "/USB PD/CC2")
	(net 34 "unconnected-(J1-D_{B}+-PadB6)")
	(net 35 "unconnected-(J1-D_{B}--PadB7)")
	(net 36 "unconnected-(J1-SBU_{2}-PadB8)")
	(net 37 "/USB PD/SDA")
	(net 38 "/USB PD/SCL")
	(net 39 "Net-(U4-FB)")
	(net 40 "Net-(U3-FB)")
	(net 41 "Net-(U1-DISCH)")
	(net 42 "Net-(U1-RESET)")
	(net 43 "/DC-DC Converters/12V_MODE")
	(net 44 "/DC-DC Converters/12V_ILIM")
	(net 45 "Net-(U2-EN)")
	(net 46 "/DC-DC Converters/12V_FSW")
	(net 47 "Net-(U3-EN)")
	(net 48 "Net-(U2-P_{GOOD})")
	(net 49 "Net-(R14-Pad2)")
	(net 50 "Net-(R16-Pad1)")
	(net 51 "Net-(U2-V_{FB})")
	(net 52 "/USB PD/VBUS_DISCH")
	(net 53 "/USB PD/VBUS_EN")
	(net 54 "Net-(U1-~{ALERT})")
	(net 55 "Net-(U1-ATTACH)")
	(net 56 "Net-(U1-A_B_SIDE)")
	(net 57 "Net-(U1-GPIO)")
	(net 58 "unconnected-(U1-NC-Pad3)")
	(net 59 "unconnected-(U2-GL-Pad15)")
	(net 60 "unconnected-(U2-NC-Pad18)")
	(net 61 "/USB PD/QWIIC_VCC")
	(net 62 "unconnected-(U6-Pad1)")
	(net 63 "Net-(D1-C)")
	(net 64 "Net-(D3-A)")
	(net 65 "Net-(D4-A)")
	(net 66 "Net-(D6-A)")
	(net 67 "Net-(D7-A)")
	(net 68 "Net-(D8-A)")
	(net 69 "Net-(D9-A)")
	(net 70 "unconnected-(U6-Pad1)_1")
	(footprint "antmicro-footprints:MP_Pad3.5mm_Drill2.2mm"
		(locked yes)
		(layer "F.Cu")
		(at 94.448823 75.686319)
		(property "Reference" "MP1"
			(at -1.103823 0.259681 0)
			(layer "F.SilkS")
			(hide yes)
			(effects
				(font
					(size 0.7 0.7)
					(thickness 0.15)
				)
				(justify left bottom)
			)
		)
		(property "Value" "MP_Pad3.5mm_Drill2.2mm"
			(at 0 2.8 0)
			(layer "F.Fab")
			(effects
				(font
					(size 0.7 0.7)
					(thickness 0.15)
				)
				(justify left bottom)
			)
		)
		(property "Description" "PCB mounting point"
			(at 0 0 0)
			(layer "F.Fab")
			(hide yes)
			(effects
				(font
					(size 1.27 1.27)
					(thickness 0.15)
				)
			)
		)
		(property "Author" "Antmicro"
			(at 0 0 0)
			(unlocked yes)
			(layer "F.Fab")
			(hide yes)
			(effects
				(font
					(size 1 1)
					(thickness 0.15)
				)
			)
		)
		(property "License" "Apache-2.0"
			(at 0 0 0)
			(unlocked yes)
			(layer "F.Fab")
			(hide yes)
			(effects
				(font
					(size 1 1)
					(thickness 0.15)
				)
			)
		)
		(sheetname "/USB PD/")
		(sheetfile "usb_pd.kicad_sch")
		(attr exclude_from_bom)
		(fp_circle
			(center 0 0)
			(end 2 0)
			(stroke
				(width 0.05)
				(type default)
			)
			(fill no)
			(layer "F.CrtYd")
		)
		(pad "1" thru_hole circle
			(at 0 0)
			(size 3.5 3.5)
			(drill 2.2)
			(layers "*.Cu" "*.Mask")
			(remove_unused_layers no)
			(net 2 "GND")
			(pintype "passive")
			(solder_paste_margin_ratio -1)
		)
	)
	(footprint "antmicro-footprints:TP_SMD_0.75mm"
		(layer "F.Cu")
		(at 82.706 74.34)
		(property "Reference" "TP10"
			(at -2.9718 -0.254 90)
			(layer "F.SilkS")
			(hide yes)
			(effects
				(font
					(size 0.7 0.7)
					(thickness 0.15)
				)
				(justify left bottom)
			)
		)
		(property "Value" "TP_0.75mm_SMD"
			(at 0 1.2 0)
			(layer "F.Fab")
			(effects
				(font
					(size 0.7 0.7)
					(thickness 0.15)
				)
				(justify left bottom)
			)
		)
		(property "Description" "SMT test point"
			(at 0 0 0)
			(layer "F.Fab")
			(hide yes)
			(effects
				(font
					(size 1.27 1.27)
					(thickness 0.15)
				)
			)
		)
		(property "MPN" ""
			(at 0 0 0)
			(unlocked yes)
			(layer "F.Fab")
			(hide yes)
			(effects
				(font
					(size 1 1)
					(thickness 0.15)
				)
			)
		)
		(property "Manufacturer" ""
			(at 0 0 0)
			(unlocked yes)
			(layer "F.Fab")
			(hide yes)
			(effects
				(font
					(size 1 1)
					(thickness 0.15)
				)
			)
		)
		(property "Author" "Antmicro"
			(at 0 0 0)
			(unlocked yes)
			(layer "F.Fab")
			(hide yes)
			(effects
				(font
					(size 1 1)
					(thickness 0.15)
				)
			)
		)
		(property "License" "Apache-2.0"
			(at 0 0 0)
			(unlocked yes)
			(layer "F.Fab")
			(hide yes)
			(effects
				(font
					(size 1 1)
					(thickness 0.15)
				)
			)
		)
		(sheetname "/USB PD/")
		(sheetfile "usb_pd.kicad_sch")
		(attr exclude_from_bom)
		(fp_circle
			(center 0 0)
			(end 0.475 0)
			(stroke
				(width 0.05)
				(type default)
			)
			(fill no)
			(layer "F.CrtYd")
		)
		(pad "1" smd circle
			(at 0 0)
			(size 0.75 0.75)
			(layers "F.Cu" "F.Mask")
			(net 55 "Net-(U1-ATTACH)")
			(pinfunction "1")
			(pintype "passive")
		)
	)
	(footprint "antmicro-footprints:R_0402_1005Metric"
		(layer "F.Cu")
		(at 100 81.577 180)
		(descr "Resistor SMD 0402")
		(tags "resistor SMD 0402")
		(property "Reference" "R7"
			(at -1.092 -0.465 0)
			(layer "F.SilkS")
			(effects
				(font
					(size 0.7 0.7)
					(thickness 0.15)
				)
				(justify left bottom)
			)
		)
		(property "Value" "R_68k_0402"
			(at -1.011843 1.772047 0)
			(layer "F.Fab")
			(effects
				(font
					(size 0.7 0.7)
					(thickness 0.15)
				)
				(justify right bottom)
			)
		)
		(property "Datasheet" "https://www.bourns.com/docs/product-datasheets/cr.pdf"
			(at 0 0 180)
			(layer "F.Fab")
			(hide yes)
			(effects
				(font
					(size 1.27 1.27)
					(thickness 0.15)
				)
			)
		)
		(property "Description" "SMD Chip Resistor"
			(at 0 0 180)
			(layer "F.Fab")
			(hide yes)
			(effects
				(font
					(size 1.27 1.27)
					(thickness 0.15)
				)
			)
		)
		(property "MPN" "CR0402-FX-6802GLF"
			(at 0 0 180)
			(unlocked yes)
			(layer "F.Fab")
			(hide yes)
			(effects
				(font
					(size 1 1)
					(thickness 0.15)
				)
			)
		)
		(property "Manufacturer" "Bourns"
			(at 0 0 180)
			(unlocked yes)
			(layer "F.Fab")
			(hide yes)
			(effects
				(font
					(size 1 1)
					(thickness 0.15)
				)
			)
		)
		(property "License" "Apache-2.0"
			(at 0 0 180)
			(unlocked yes)
			(layer "F.Fab")
			(hide yes)
			(effects
				(font
					(size 1 1)
					(thickness 0.15)
				)
			)
		)
		(property "Author" "Antmicro"
			(at 0 0 180)
			(unlocked yes)
			(layer "F.Fab")
			(hide yes)
			(effects
				(font
					(size 1 1)
					(thickness 0.15)
				)
			)
		)
		(property "Val" "68k"
			(at 0 0 180)
			(unlocked yes)
			(layer "F.Fab")
			(hide yes)
			(effects
				(font
					(size 1 1)
					(thickness 0.15)
				)
			)
		)
		(property "Tolerance" "1%"
			(at 0 0 180)
			(unlocked yes)
			(layer "F.Fab")
			(hide yes)
			(effects
				(font
					(size 1 1)
					(thickness 0.15)
				)
			)
		)
		(sheetname "/DC-DC Converters/")
		(sheetfile "dc-dc_converters.kicad_sch")
		(attr smd exclude_from_pos_files exclude_from_bom dnp)
		(fp_rect
			(start -0.925 -0.47)
			(end 0.925 0.47)
			(stroke
				(width 0.05)
				(type default)
			)
			(fill no)
			(layer "F.CrtYd")
		)
		(fp_rect
			(start -0.5 -0.25)
			(end 0.5 0.25)
			(stroke
				(width 0.15)
				(type solid)
			)
			(fill no)
			(layer "F.Fab")
		)
		(pad "1" smd roundrect
			(at -0.48 0 180)
			(size 0.59 0.64)
			(layers "F.Cu" "F.Mask" "F.Paste")
			(roundrect_rratio 0.25)
			(net 2 "GND")
			(pintype "passive")
		)
		(pad "2" smd roundrect
			(at 0.48 0 180)
			(size 0.59 0.64)
			(layers "F.Cu" "F.Mask" "F.Paste")
			(roundrect_rratio 0.25)
			(net 44 "/DC-DC Converters/12V_ILIM")
			(pintype "passive")
		)
	)
	(footprint "antmicro-footprints:C_0402_1005Metric"
		(layer "F.Cu")
		(at 89.4 73.7 180)
		(descr "Capacitor SMD 0402")
		(tags "capacitor SMD 0402")
		(property "Reference" "C9"
			(at -6.3912 2.35 90)
			(layer "B.SilkS")
			(effects
				(font
					(size 0.7 0.7)
					(thickness 0.15)
				)
				(justify left bottom mirror)
			)
		)
		(property "Value" "C_1u_25V_0402"
			(at -1.022927 2.155213 0)
			(layer "F.Fab")
			(effects
				(font
					(size 0.7 0.7)
					(thickness 0.15)
				)
				(justify right bottom)
			)
		)
		(property "Datasheet" "https://www.murata.com/products/productdetail?partno=GRM155R61E105KE11%23"
			(at 0 0 180)
			(layer "F.Fab")
			(hide yes)
			(effects
				(font
					(size 1.27 1.27)
					(thickness 0.15)
				)
			)
		)
		(property "Description" "SMD Multilayer Ceramic Capacitor, 1 µF, 25 V, 0402 [1005 Metric], ± 10%, X5R, GRM Series"
			(at 0 0 180)
			(layer "F.Fab")
			(hide yes)
			(effects
				(font
					(size 1.27 1.27)
					(thickness 0.15)
				)
			)
		)
		(property "MPN" "GRM155R61E105KE11J"
			(at 0 0 180)
			(unlocked yes)
			(layer "F.Fab")
			(hide yes)
			(effects
				(font
					(size 1 1)
					(thickness 0.15)
				)
			)
		)
		(property "Manufacturer" "Murata"
			(at 0 0 180)
			(unlocked yes)
			(layer "F.Fab")
			(hide yes)
			(effects
				(font
					(size 1 1)
					(thickness 0.15)
				)
			)
		)
		(property "License" "Apache-2.0"
			(at 0 0 180)
			(unlocked yes)
			(layer "F.Fab")
			(hide yes)
			(effects
				(font
					(size 1 1)
					(thickness 0.15)
				)
			)
		)
		(property "Author" "Antmicro"
			(at 0 0 180)
			(unlocked yes)
			(layer "F.Fab")
			(hide yes)
			(effects
				(font
					(size 1 1)
					(thickness 0.15)
				)
			)
		)
		(property "Val" "1u"
			(at 0 0 180)
			(unlocked yes)
			(layer "F.Fab")
			(hide yes)
			(effects
				(font
					(size 1 1)
					(thickness 0.15)
				)
			)
		)
		(property "Voltage" "25V"
			(at 0 0 180)
			(unlocked yes)
			(layer "F.Fab")
			(hide yes)
			(effects
				(font
					(size 1 1)
					(thickness 0.15)
				)
			)
		)
		(property "Dielectric" "X5R"
			(at 0 0 180)
			(unlocked yes)
			(layer "F.Fab")
			(hide yes)
			(effects
				(font
					(size 1 1)
					(thickness 0.15)
				)
			)
		)
		(sheetname "/USB PD/")
		(sheetfile "usb_pd.kicad_sch")
		(attr smd)
		(fp_rect
			(start -0.925 -0.47)
			(end 0.925 0.47)
			(stroke
				(width 0.05)
				(type default)
			)
			(fill no)
			(layer "F.CrtYd")
		)
		(fp_line
			(start 0.504 0.248)
			(end -0.494 0.248)
			(stroke
				(width 0.15)
				(type solid)
			)
			(layer "F.Fab")
		)
		(fp_line
			(start 0.504 -0.25)
			(end 0.504 0.248)
			(stroke
				(width 0.15)
				(type solid)
			)
			(layer "F.Fab")
		)
		(fp_line
			(start -0.494 0.248)
			(end -0.494 -0.25)
			(stroke
				(width 0.15)
				(type solid)
			)
			(layer "F.Fab")
		)
		(fp_line
			(start -0.494 -0.25)
			(end 0.504 -0.25)
			(stroke
				(width 0.15)
				(type solid)
			)
			(layer "F.Fab")
		)
		(pad "1" smd roundrect
			(at -0.48 0 180)
			(size 0.59 0.64)
			(layers "F.Cu" "F.Mask" "F.Paste")
			(roundrect_rratio 0.25)
			(net 2 "GND")
			(pintype "passive")
		)
		(pad "2" smd roundrect
			(at 0.48 0 180)
			(size 0.59 0.64)
			(layers "F.Cu" "F.Mask" "F.Paste")
			(roundrect_rratio 0.25)
			(net 15 "Net-(U1-VREG_1V2)")
			(pintype "passive")
		)
	)
	(footprint "antmicro-footprints:TP_SMD_0.75mm"
		(layer "F.Cu")
		(at 87.126 81.275)
		(property "Reference" "TP4"
			(at 13.956 -3.4 0)
			(layer "F.SilkS")
			(hide yes)
			(effects
				(font
					(size 0.7 0.7)
					(thickness 0.15)
				)
				(justify left bottom)
			)
		)
		(property "Value" "TP_0.75mm_SMD"
			(at 0 1.2 0)
			(layer "F.Fab")
			(effects
				(font
					(size 0.7 0.7)
					(thickness 0.15)
				)
				(justify left bottom)
			)
		)
		(property "Description" "SMT test point"
			(at 0 0 0)
			(layer "F.Fab")
			(hide yes)
			(effects
				(font
					(size 1.27 1.27)
					(thickness 0.15)
				)
			)
		)
		(property "MPN" ""
			(at 0 0 0)
			(unlocked yes)
			(layer "F.Fab")
			(hide yes)
			(effects
				(font
					(size 1 1)
					(thickness 0.15)
				)
			)
		)
		(property "Manufacturer" ""
			(at 0 0 0)
			(unlocked yes)
			(layer "F.Fab")
			(hide yes)
			(effects
				(font
					(size 1 1)
					(thickness 0.15)
				)
			)
		)
		(property "Author" "Antmicro"
			(at 0 0 0)
			(unlocked yes)
			(layer "F.Fab")
			(hide yes)
			(effects
				(font
					(size 1 1)
					(thickness 0.15)
				)
			)
		)
		(property "License" "Apache-2.0"
			(at 0 0 0)
			(unlocked yes)
			(layer "F.Fab")
			(hide yes)
			(effects
				(font
					(size 1 1)
					(thickness 0.15)
				)
			)
		)
		(sheetname "/USB PD/")
		(sheetfile "usb_pd.kicad_sch")
		(attr exclude_from_bom)
		(fp_circle
			(center 0 0)
			(end 0.475 0)
			(stroke
				(width 0.05)
				(type default)
			)
			(fill no)
			(layer "F.CrtYd")
		)
		(pad "1" smd circle
			(at 0 0)
			(size 0.75 0.75)
			(layers "F.Cu" "F.Mask")
			(net 3 "VCC")
			(pinfunction "1")
			(pintype "passive")
		)
	)
	(footprint "antmicro-footprints:R_0402_1005Metric"
		(layer "F.Cu")
		(at 91.851 106.05 90)
		(descr "Resistor SMD 0402")
		(tags "resistor SMD 0402")
		(property "Reference" "R28"
			(at -1.075 -0.725 90)
			(layer "F.SilkS")
			(effects
				(font
					(size 0.7 0.7)
					(thickness 0.15)
				)
				(justify left bottom)
			)
		)
		(property "Value" "R_2k2_0402"
			(at -1.011843 1.772047 90)
			(layer "F.Fab")
			(effects
				(font
					(size 0.7 0.7)
					(thickness 0.15)
				)
				(justify left bottom)
			)
		)
		(property "Datasheet" "https://www.bourns.com/docs/product-datasheets/cr.pdf"
			(at 0 0 90)
			(layer "F.Fab")
			(hide yes)
			(effects
				(font
					(size 1.27 1.27)
					(thickness 0.15)
				)
			)
		)
		(property "Description" "SMD Chip Resistor, 2.2 kohm, ± 1%, 62.5 mW, 0402 [1005 Metric], Thick Film, General Purpose"
			(at 0 0 90)
			(layer "F.Fab")
			(hide yes)
			(effects
				(font
					(size 1.27 1.27)
					(thickness 0.15)
				)
			)
		)
		(property "MPN" "CR0402-FX-2201GLF"
			(at 0 0 90)
			(unlocked yes)
			(layer "F.Fab")
			(hide yes)
			(effects
				(font
					(size 1 1)
					(thickness 0.15)
				)
			)
		)
		(property "Manufacturer" "Bourns"
			(at 0 0 90)
			(unlocked yes)
			(layer "F.Fab")
			(hide yes)
			(effects
				(font
					(size 1 1)
					(thickness 0.15)
				)
			)
		)
		(property "License" "Apache-2.0"
			(at 0 0 90)
			(unlocked yes)
			(layer "F.Fab")
			(hide yes)
			(effects
				(font
					(size 1 1)
					(thickness 0.15)
				)
			)
		)
		(property "Author" "Antmicro"
			(at 0 0 90)
			(unlocked yes)
			(layer "F.Fab")
			(hide yes)
			(effects
				(font
					(size 1 1)
					(thickness 0.15)
				)
			)
		)
		(property "Val" "2k2"
			(at 0 0 90)
			(unlocked yes)
			(layer "F.Fab")
			(hide yes)
			(effects
				(font
					(size 1 1)
					(thickness 0.15)
				)
			)
		)
		(property "Tolerance" "1%"
			(at 0 0 90)
			(unlocked yes)
			(layer "F.Fab")
			(hide yes)
			(effects
				(font
					(size 1 1)
					(thickness 0.15)
				)
			)
		)
		(sheetname "/DC-DC Converters/")
		(sheetfile "dc-dc_converters.kicad_sch")
		(attr smd)
		(fp_rect
			(start -0.925 -0.47)
			(end 0.925 0.47)
			(stroke
				(width 0.05)
				(type default)
			)
			(fill no)
			(layer "F.CrtYd")
		)
		(fp_rect
			(start -0.5 -0.25)
			(end 0.5 0.25)
			(stroke
				(width 0.15)
				(type solid)
			)
			(fill no)
			(layer "F.Fab")
		)
		(pad "1" smd roundrect
			(at -0.48 0 90)
			(size 0.59 0.64)
			(layers "F.Cu" "F.Mask" "F.Paste")
			(roundrect_rratio 0.25)
			(net 65 "Net-(D4-A)")
			(pintype "passive")
		)
		(pad "2" smd roundrect
			(at 0.48 0 90)
			(size 0.59 0.64)
			(layers "F.Cu" "F.Mask" "F.Paste")
			(roundrect_rratio 0.25)
			(net 5 "+12V")
			(pintype "passive")
		)
	)
	(footprint "antmicro-footprints:TP_SMD_0.75mm"
		(layer "F.Cu")
		(at 89.676 105.05)
		(property "Reference" "TP7"
			(at -12.203 -1.909 0)
			(layer "F.SilkS")
			(hide yes)
			(effects
				(font
					(size 0.7 0.7)
					(thickness 0.15)
				)
				(justify left bottom)
			)
		)
		(property "Value" "TP_0.75mm_SMD"
			(at 0 1.2 0)
			(layer "F.Fab")
			(effects
				(font
					(size 0.7 0.7)
					(thickness 0.15)
				)
				(justify left bottom)
			)
		)
		(property "Description" "SMT test point"
			(at 0 0 0)
			(layer "F.Fab")
			(hide yes)
			(effects
				(font
					(size 1.27 1.27)
					(thickness 0.15)
				)
			)
		)
		(property "MPN" ""
			(at 0 0 0)
			(unlocked yes)
			(layer "F.Fab")
			(hide yes)
			(effects
				(font
					(size 1 1)
					(thickness 0.15)
				)
			)
		)
		(property "Manufacturer" ""
			(at 0 0 0)
			(unlocked yes)
			(layer "F.Fab")
			(hide yes)
			(effects
				(font
					(size 1 1)
					(thickness 0.15)
				)
			)
		)
		(property "Author" "Antmicro"
			(at 0 0 0)
			(unlocked yes)
			(layer "F.Fab")
			(hide yes)
			(effects
				(font
					(size 1 1)
					(thickness 0.15)
				)
			)
		)
		(property "License" "Apache-2.0"
			(at 0 0 0)
			(unlocked yes)
			(layer "F.Fab")
			(hide yes)
			(effects
				(font
					(size 1 1)
					(thickness 0.15)
				)
			)
		)
		(sheetname "/DC-DC Converters/")
		(sheetfile "dc-dc_converters.kicad_sch")
		(attr exclude_from_bom)
		(fp_circle
			(center 0 0)
			(end 0.475 0)
			(stroke
				(width 0.05)
				(type default)
			)
			(fill no)
			(layer "F.CrtYd")
		)
		(pad "1" smd circle
			(at 0 0)
			(size 0.75 0.75)
			(layers "F.Cu" "F.Mask")
			(net 5 "+12V")
			(pinfunction "1")
			(pintype "passive")
		)
	)
	(footprint "antmicro-footprints:R_0402_1005Metric"
		(layer "F.Cu")
		(at 100.5 89.6 180)
		(descr "Resistor SMD 0402")
		(tags "resistor SMD 0402")
		(property "Reference" "R15"
			(at -1.8 -1.2 90)
			(layer "F.SilkS")
			(effects
				(font
					(size 0.7 0.7)
					(thickness 0.15)
				)
				(justify left bottom)
			)
		)
		(property "Value" "R_8k66_0402"
			(at -1.011843 1.772047 0)
			(layer "F.Fab")
			(effects
				(font
					(size 0.7 0.7)
					(thickness 0.15)
				)
				(justify right bottom)
			)
		)
		(property "Datasheet" "https://www.bourns.com/docs/product-datasheets/cr.pdf"
			(at 0 0 180)
			(layer "F.Fab")
			(hide yes)
			(effects
				(font
					(size 1.27 1.27)
					(thickness 0.15)
				)
			)
		)
		(property "Description" "SMD Chip Resistor"
			(at 0 0 180)
			(layer "F.Fab")
			(hide yes)
			(effects
				(font
					(size 1.27 1.27)
					(thickness 0.15)
				)
			)
		)
		(property "Manufacturer" "Bourns"
			(at 0 0 180)
			(unlocked yes)
			(layer "F.Fab")
			(hide yes)
			(effects
				(font
					(size 1 1)
					(thickness 0.15)
				)
			)
		)
		(property "MPN" "CR0402-FX-8661GLF"
			(at 0 0 180)
			(unlocked yes)
			(layer "F.Fab")
			(hide yes)
			(effects
				(font
					(size 1 1)
					(thickness 0.15)
				)
			)
		)
		(property "Val" "8k66"
			(at 0 0 180)
			(unlocked yes)
			(layer "F.Fab")
			(hide yes)
			(effects
				(font
					(size 1 1)
					(thickness 0.15)
				)
			)
		)
		(property "License" "Apache-2.0"
			(at 0 0 180)
			(unlocked yes)
			(layer "F.Fab")
			(hide yes)
			(effects
				(font
					(size 1 1)
					(thickness 0.15)
				)
			)
		)
		(property "Author" "Antmicro"
			(at 0 0 180)
			(unlocked yes)
			(layer "F.Fab")
			(hide yes)
			(effects
				(font
					(size 1 1)
					(thickness 0.15)
				)
			)
		)
		(property "Tolerance" "1%"
			(at 0 0 180)
			(unlocked yes)
			(layer "F.Fab")
			(hide yes)
			(effects
				(font
					(size 1 1)
					(thickness 0.15)
				)
			)
		)
		(sheetname "/DC-DC Converters/")
		(sheetfile "dc-dc_converters.kicad_sch")
		(attr smd exclude_from_pos_files exclude_from_bom dnp)
		(fp_rect
			(start -0.925 -0.47)
			(end 0.925 0.47)
			(stroke
				(width 0.05)
				(type default)
			)
			(fill no)
			(layer "F.CrtYd")
		)
		(fp_rect
			(start -0.5 -0.25)
			(end 0.5 0.25)
			(stroke
				(width 0.15)
				(type solid)
			)
			(fill no)
			(layer "F.Fab")
		)
		(pad "1" smd roundrect
			(at -0.48 0 180)
			(size 0.59 0.64)
			(layers "F.Cu" "F.Mask" "F.Paste")
			(roundrect_rratio 0.25)
			(net 8 "Net-(L1-Pad1)")
			(pintype "passive")
		)
		(pad "2" smd roundrect
			(at 0.48 0 180)
			(size 0.59 0.64)
			(layers "F.Cu" "F.Mask" "F.Paste")
			(roundrect_rratio 0.25)
			(net 19 "/DC-DC Converters/12V_SNS")
			(pintype "passive")
		)
	)
	(footprint "antmicro-footprints:R_0402_1005Metric"
		(layer "F.Cu")
		(at 98.1 89 -90)
		(descr "Resistor SMD 0402")
		(tags "resistor SMD 0402")
		(property "Reference" "R12"
			(at 1.8 2.5 90)
			(layer "F.SilkS")
			(effects
				(font
					(size 0.7 0.7)
					(thickness 0.15)
				)
				(justify left bottom)
			)
		)
		(property "Value" "R_0R_0402"
			(at -1.011843 1.772047 90)
			(layer "F.Fab")
			(effects
				(font
					(size 0.7 0.7)
					(thickness 0.15)
				)
				(justify right bottom)
			)
		)
		(property "Datasheet" "https://industrial.panasonic.com/cdbs/www-data/pdf/RDA0000/AOA0000C301.pdf"
			(at 0 0 270)
			(layer "F.Fab")
			(hide yes)
			(effects
				(font
					(size 1.27 1.27)
					(thickness 0.15)
				)
			)
		)
		(property "Description" "SMD Chip Resistor, Jumper, 0 ohm, 100 mW, 0402 [1005 Metric], Thick Film, General Purpose"
			(at 0 0 270)
			(layer "F.Fab")
			(hide yes)
			(effects
				(font
					(size 1.27 1.27)
					(thickness 0.15)
				)
			)
		)
		(property "Manufacturer" "Panasonic"
			(at 0 0 270)
			(unlocked yes)
			(layer "F.Fab")
			(hide yes)
			(effects
				(font
					(size 1 1)
					(thickness 0.15)
				)
			)
		)
		(property "MPN" "ERJ2GE0R00X"
			(at 0 0 270)
			(unlocked yes)
			(layer "F.Fab")
			(hide yes)
			(effects
				(font
					(size 1 1)
					(thickness 0.15)
				)
			)
		)
		(property "Val" "0R"
			(at 0 0 270)
			(unlocked yes)
			(layer "F.Fab")
			(hide yes)
			(effects
				(font
					(size 1 1)
					(thickness 0.15)
				)
			)
		)
		(property "License" "Apache-2.0"
			(at 0 0 270)
			(unlocked yes)
			(layer "F.Fab")
			(hide yes)
			(effects
				(font
					(size 1 1)
					(thickness 0.15)
				)
			)
		)
		(property "Author" "Antmicro"
			(at 0 0 270)
			(unlocked yes)
			(layer "F.Fab")
			(hide yes)
			(effects
				(font
					(size 1 1)
					(thickness 0.15)
				)
			)
		)
		(property "Tolerance" ""
			(at 0 0 270)
			(unlocked yes)
			(layer "F.Fab")
			(hide yes)
			(effects
				(font
					(size 1 1)
					(thickness 0.15)
				)
			)
		)
		(property "Current" "1A"
			(at 0 0 270)
			(unlocked yes)
			(layer "F.Fab")
			(hide yes)
			(effects
				(font
					(size 1 1)
					(thickness 0.15)
				)
			)
		)
		(sheetname "/DC-DC Converters/")
		(sheetfile "dc-dc_converters.kicad_sch")
		(attr smd)
		(fp_rect
			(start -0.925 -0.47)
			(end 0.925 0.47)
			(stroke
				(width 0.05)
				(type default)
			)
			(fill no)
			(layer "F.CrtYd")
		)
		(fp_rect
			(start -0.5 -0.25)
			(end 0.5 0.25)
			(stroke
				(width 0.15)
				(type solid)
			)
			(fill no)
			(layer "F.Fab")
		)
		(pad "1" smd roundrect
			(at -0.48 0 270)
			(size 0.59 0.64)
			(layers "F.Cu" "F.Mask" "F.Paste")
			(roundrect_rratio 0.25)
			(net 18 "Net-(U2-V_{SNS})")
			(pintype "passive")
		)
		(pad "2" smd roundrect
			(at 0.48 0 270)
			(size 0.59 0.64)
			(layers "F.Cu" "F.Mask" "F.Paste")
			(roundrect_rratio 0.25)
			(net 5 "+12V")
			(pintype "passive")
		)
	)
	(footprint "antmicro-footprints:C_0402_1005Metric"
		(layer "F.Cu")
		(at 99.05 89 -90)
		(descr "Capacitor SMD 0402")
		(tags "capacitor SMD 0402")
		(property "Reference" "C12"
			(at 1.8 2.45 90)
			(layer "F.SilkS")
			(effects
				(font
					(size 0.7 0.7)
					(thickness 0.15)
				)
				(justify left bottom)
			)
		)
		(property "Value" "C_1n2_50V_0402"
			(at -1.022927 2.155213 90)
			(layer "F.Fab")
			(effects
				(font
					(size 0.7 0.7)
					(thickness 0.15)
				)
				(justify right bottom)
			)
		)
		(property "Datasheet" "https://www.murata.com/products/productdetail?partno=GCM155R71H122KA37%23"
			(at 0 0 270)
			(layer "F.Fab")
			(hide yes)
			(effects
				(font
					(size 1.27 1.27)
					(thickness 0.15)
				)
			)
		)
		(property "Description" "SMD Multilayer Ceramic Capacitor, 1200 pF, 50 V, 0402 [1005 Metric], ± 10%, X7R, GCM"
			(at 0 0 270)
			(layer "F.Fab")
			(hide yes)
			(effects
				(font
					(size 1.27 1.27)
					(thickness 0.15)
				)
			)
		)
		(property "Manufacturer" "Murata"
			(at 0 0 270)
			(unlocked yes)
			(layer "F.Fab")
			(hide yes)
			(effects
				(font
					(size 1 1)
					(thickness 0.15)
				)
			)
		)
		(property "MPN" "GCM155R71H122KA37D"
			(at 0 0 270)
			(unlocked yes)
			(layer "F.Fab")
			(hide yes)
			(effects
				(font
					(size 1 1)
					(thickness 0.15)
				)
			)
		)
		(property "Val" "1n2"
			(at 0 0 270)
			(unlocked yes)
			(layer "F.Fab")
			(hide yes)
			(effects
				(font
					(size 1 1)
					(thickness 0.15)
				)
			)
		)
		(property "License" "Apache-2.0"
			(at 0 0 270)
			(unlocked yes)
			(layer "F.Fab")
			(hide yes)
			(effects
				(font
					(size 1 1)
					(thickness 0.15)
				)
			)
		)
		(property "Author" "Antmicro"
			(at 0 0 270)
			(unlocked yes)
			(layer "F.Fab")
			(hide yes)
			(effects
				(font
					(size 1 1)
					(thickness 0.15)
				)
			)
		)
		(property "Voltage" "50V"
			(at 0 0 270)
			(unlocked yes)
			(layer "F.Fab")
			(hide yes)
			(effects
				(font
					(size 1 1)
					(thickness 0.15)
				)
			)
		)
		(property "Dielectric" ""
			(at 0 0 270)
			(unlocked yes)
			(layer "F.Fab")
			(hide yes)
			(effects
				(font
					(size 1 1)
					(thickness 0.15)
				)
			)
		)
		(sheetname "/DC-DC Converters/")
		(sheetfile "dc-dc_converters.kicad_sch")
		(attr smd exclude_from_pos_files exclude_from_bom dnp)
		(fp_rect
			(start -0.925 -0.47)
			(end 0.925 0.47)
			(stroke
				(width 0.05)
				(type default)
			)
			(fill no)
			(layer "F.CrtYd")
		)
		(fp_line
			(start -0.494 0.248)
			(end -0.494 -0.25)
			(stroke
				(width 0.15)
				(type solid)
			)
			(layer "F.Fab")
		)
		(fp_line
			(start 0.504 0.248)
			(end -0.494 0.248)
			(stroke
				(width 0.15)
				(type solid)
			)
			(layer "F.Fab")
		)
		(fp_line
			(start -0.494 -0.25)
			(end 0.504 -0.25)
			(stroke
				(width 0.15)
				(type solid)
			)
			(layer "F.Fab")
		)
		(fp_line
			(start 0.504 -0.25)
			(end 0.504 0.248)
			(stroke
				(width 0.15)
				(type solid)
			)
			(layer "F.Fab")
		)
		(pad "1" smd roundrect
			(at -0.48 0 270)
			(size 0.59 0.64)
			(layers "F.Cu" "F.Mask" "F.Paste")
			(roundrect_rratio 0.25)
			(net 18 "Net-(U2-V_{SNS})")
			(pintype "passive")
		)
		(pad "2" smd roundrect
			(at 0.48 0 270)
			(size 0.59 0.64)
			(layers "F.Cu" "F.Mask" "F.Paste")
			(roundrect_rratio 0.25)
			(net 19 "/DC-DC Converters/12V_SNS")
			(pintype "passive")
		)
	)
	(footprint "antmicro-footprints:C_0402_1005Metric"
		(layer "F.Cu")
		(at 97.1 89 -90)
		(descr "Capacitor SMD 0402")
		(tags "capacitor SMD 0402")
		(property "Reference" "C5"
			(at 1.8 2.5 90)
			(layer "F.SilkS")
			(effects
				(font
					(size 0.7 0.7)
					(thickness 0.15)
				)
				(justify left bottom)
			)
		)
		(property "Value" "C_33n_0402"
			(at -1.022927 2.155213 90)
			(layer "F.Fab")
			(effects
				(font
					(size 0.7 0.7)
					(thickness 0.15)
				)
				(justify right bottom)
			)
		)
		(property "Datasheet" "https://www.murata.com/products/productdetail?partno=GCM155R71E333KA55%23"
			(at 0 0 270)
			(layer "F.Fab")
			(hide yes)
			(effects
				(font
					(size 1.27 1.27)
					(thickness 0.15)
				)
			)
		)
		(property "Description" "SMD Multilayer Ceramic Capacitor, 33000 pF, 25 V, 0402 [1005 Metric], ± 10%, X7R, MC"
			(at 0 0 270)
			(layer "F.Fab")
			(hide yes)
			(effects
				(font
					(size 1.27 1.27)
					(thickness 0.15)
				)
			)
		)
		(property "Manufacturer" "Murata"
			(at 0 0 270)
			(unlocked yes)
			(layer "F.Fab")
			(hide yes)
			(effects
				(font
					(size 1 1)
					(thickness 0.15)
				)
			)
		)
		(property "MPN" "GCM155R71E333KA55D"
			(at 0 0 270)
			(unlocked yes)
			(layer "F.Fab")
			(hide yes)
			(effects
				(font
					(size 1 1)
					(thickness 0.15)
				)
			)
		)
		(property "Val" "33n"
			(at 0 0 270)
			(unlocked yes)
			(layer "F.Fab")
			(hide yes)
			(effects
				(font
					(size 1 1)
					(thickness 0.15)
				)
			)
		)
		(property "License" "Apache-2.0"
			(at 0 0 270)
			(unlocked yes)
			(layer "F.Fab")
			(hide yes)
			(effects
				(font
					(size 1 1)
					(thickness 0.15)
				)
			)
		)
		(property "Author" "Antmicro"
			(at 0 0 270)
			(unlocked yes)
			(layer "F.Fab")
			(hide yes)
			(effects
				(font
					(size 1 1)
					(thickness 0.15)
				)
			)
		)
		(property "Voltage" ""
			(at 0 0 270)
			(unlocked yes)
			(layer "F.Fab")
			(hide yes)
			(effects
				(font
					(size 1 1)
					(thickness 0.15)
				)
			)
		)
		(property "Dielectric" ""
			(at 0 0 270)
			(unlocked yes)
			(layer "F.Fab")
			(hide yes)
			(effects
				(font
					(size 1 1)
					(thickness 0.15)
				)
			)
		)
		(sheetname "/DC-DC Converters/")
		(sheetfile "dc-dc_converters.kicad_sch")
		(attr smd)
		(fp_rect
			(start -0.925 -0.47)
			(end 0.925 0.47)
			(stroke
				(width 0.05)
				(type default)
			)
			(fill no)
			(layer "F.CrtYd")
		)
		(fp_line
			(start -0.494 0.248)
			(end -0.494 -0.25)
			(stroke
				(width 0.15)
				(type solid)
			)
			(layer "F.Fab")
		)
		(fp_line
			(start 0.504 0.248)
			(end -0.494 0.248)
			(stroke
				(width 0.15)
				(type solid)
			)
			(layer "F.Fab")
		)
		(fp_line
			(start -0.494 -0.25)
			(end 0.504 -0.25)
			(stroke
				(width 0.15)
				(type solid)
			)
			(layer "F.Fab")
		)
		(fp_line
			(start 0.504 -0.25)
			(end 0.504 0.248)
			(stroke
				(width 0.15)
				(type solid)
			)
			(layer "F.Fab")
		)
		(pad "1" smd roundrect
			(at -0.48 0 270)
			(size 0.59 0.64)
			(layers "F.Cu" "F.Mask" "F.Paste")
			(roundrect_rratio 0.25)
			(net 13 "/DC-DC Converters/12V_SS")
			(pintype "passive")
		)
		(pad "2" smd roundrect
			(at 0.48 0 270)
			(size 0.59 0.64)
			(layers "F.Cu" "F.Mask" "F.Paste")
			(roundrect_rratio 0.25)
			(net 2 "GND")
			(pintype "passive")
		)
	)
	(footprint "antmicro-footprints:R_0402_1005Metric"
		(layer "F.Cu")
		(at 97.8 80.3 90)
		(descr "Resistor SMD 0402")
		(tags "resistor SMD 0402")
		(property "Reference" "R5"
			(at -3.8819 5.0514 180)
			(layer "B.SilkS")
			(effects
				(font
					(size 0.7 0.7)
					(thickness 0.15)
				)
				(justify left bottom mirror)
			)
		)
		(property "Value" "R_2k_0402"
			(at -1.011843 1.772047 90)
			(layer "F.Fab")
			(effects
				(font
					(size 0.7 0.7)
					(thickness 0.15)
				)
				(justify left bottom)
			)
		)
		(property "Datasheet" "https://www.bourns.com/docs/product-datasheets/cr.pdf"
			(at 0 0 90)
			(layer "F.Fab")
			(hide yes)
			(effects
				(font
					(size 1.27 1.27)
					(thickness 0.15)
				)
			)
		)
		(property "Description" "SMD Chip Resistor, 2 kohm, ± 1%, 62.5 mW, 0402 [1005 Metric], Thick Film, General Purpose"
			(at 0 0 90)
			(layer "F.Fab")
			(hide yes)
			(effects
				(font
					(size 1.27 1.27)
					(thickness 0.15)
				)
			)
		)
		(property "Manufacturer" "Bourns"
			(at 0 0 90)
			(unlocked yes)
			(layer "F.Fab")
			(hide yes)
			(effects
				(font
					(size 1 1)
					(thickness 0.15)
				)
			)
		)
		(property "MPN" "CR0402-FX-2001GLF"
			(at 0 0 90)
			(unlocked yes)
			(layer "F.Fab")
			(hide yes)
			(effects
				(font
					(size 1 1)
					(thickness 0.15)
				)
			)
		)
		(property "Val" "2k"
			(at 0 0 90)
			(unlocked yes)
			(layer "F.Fab")
			(hide yes)
			(effects
				(font
					(size 1 1)
					(thickness 0.15)
				)
			)
		)
		(property "License" "Apache-2.0"
			(at 0 0 90)
			(unlocked yes)
			(layer "F.Fab")
			(hide yes)
			(effects
				(font
					(size 1 1)
					(thickness 0.15)
				)
			)
		)
		(property "Author" "Antmicro"
			(at 0 0 90)
			(unlocked yes)
			(layer "F.Fab")
			(hide yes)
			(effects
				(font
					(size 1 1)
					(thickness 0.15)
				)
			)
		)
		(property "Tolerance" "1%"
			(at 0 0 90)
			(unlocked yes)
			(layer "F.Fab")
			(hide yes)
			(effects
				(font
					(size 1 1)
					(thickness 0.15)
				)
			)
		)
		(sheetname "/DC-DC Converters/")
		(sheetfile "dc-dc_converters.kicad_sch")
		(attr smd)
		(fp_rect
			(start -0.925 -0.47)
			(end 0.925 0.47)
			(stroke
				(width 0.05)
				(type default)
			)
			(fill no)
			(layer "F.CrtYd")
		)
		(fp_rect
			(start -0.5 -0.25)
			(end 0.5 0.25)
			(stroke
				(width 0.15)
				(type solid)
			)
			(fill no)
			(layer "F.Fab")
		)
		(pad "1" smd roundrect
			(at -0.48 0 90)
			(size 0.59 0.64)
			(layers "F.Cu" "F.Mask" "F.Paste")
			(roundrect_rratio 0.25)
			(net 43 "/DC-DC Converters/12V_MODE")
			(pintype "passive")
		)
		(pad "2" smd roundrect
			(at 0.48 0 90)
			(size 0.59 0.64)
			(layers "F.Cu" "F.Mask" "F.Paste")
			(roundrect_rratio 0.25)
			(net 2 "GND")
			(pintype "passive")
		)
	)
	(footprint "antmicro-footprints:C_0402_1005Metric"
		(layer "F.Cu")
		(at 91.5 81.8 -90)
		(descr "Capacitor SMD 0402")
		(tags "capacitor SMD 0402")
		(property "Reference" "C6"
			(at -1.8 -0.5 0)
			(layer "F.SilkS")
			(effects
				(font
					(size 0.7 0.7)
					(thickness 0.15)
				)
				(justify right bottom)
			)
		)
		(property "Value" "C_100n_50V_X8L_0402"
			(at -1.022927 2.155213 90)
			(layer "F.Fab")
			(effects
				(font
					(size 0.7 0.7)
					(thickness 0.15)
				)
				(justify right bottom)
			)
		)
		(property "Datasheet" "https://www.murata.com/products/productdetail?partno=GCM155L8EH104KE07%23"
			(at 0 0 270)
			(layer "F.Fab")
			(hide yes)
			(effects
				(font
					(size 1.27 1.27)
					(thickness 0.15)
				)
			)
		)
		(property "Description" "SMD Multilayer Ceramic Capacitor, 100nF, 50V, 0402, ±10%, X8L"
			(at 0 0 270)
			(layer "F.Fab")
			(hide yes)
			(effects
				(font
					(size 1.27 1.27)
					(thickness 0.15)
				)
			)
		)
		(property "MPN" "GCM155L8EH104KE07D"
			(at 0 0 270)
			(unlocked yes)
			(layer "F.Fab")
			(hide yes)
			(effects
				(font
					(size 1 1)
					(thickness 0.15)
				)
			)
		)
		(property "Val" "100n"
			(at 0 0 270)
			(unlocked yes)
			(layer "F.Fab")
			(hide yes)
			(effects
				(font
					(size 1 1)
					(thickness 0.15)
				)
			)
		)
		(property "Voltage" "50V"
			(at 0 0 270)
			(unlocked yes)
			(layer "F.Fab")
			(hide yes)
			(effects
				(font
					(size 1 1)
					(thickness 0.15)
				)
			)
		)
		(property "Dielectric" "X8L"
			(at 0 0 270)
			(unlocked yes)
			(layer "F.Fab")
			(hide yes)
			(effects
				(font
					(size 1 1)
					(thickness 0.15)
				)
			)
		)
		(property "Manufacturer" "Murata"
			(at 0 0 270)
			(unlocked yes)
			(layer "F.Fab")
			(hide yes)
			(effects
				(font
					(size 1 1)
					(thickness 0.15)
				)
			)
		)
		(property "License" "Apache-2.0"
			(at 0 0 270)
			(unlocked yes)
			(layer "F.Fab")
			(hide yes)
			(effects
				(font
					(size 1 1)
					(thickness 0.15)
				)
			)
		)
		(property "Author" "Antmicro"
			(at 0 0 270)
			(unlocked yes)
			(layer "F.Fab")
			(hide yes)
			(effects
				(font
					(size 1 1)
					(thickness 0.15)
				)
			)
		)
		(sheetname "/DC-DC Converters/")
		(sheetfile "dc-dc_converters.kicad_sch")
		(attr smd)
		(fp_rect
			(start -0.925 -0.47)
			(end 0.925 0.47)
			(stroke
				(width 0.05)
				(type default)
			)
			(fill no)
			(layer "F.CrtYd")
		)
		(fp_line
			(start -0.494 0.248)
			(end -0.494 -0.25)
			(stroke
				(width 0.15)
				(type solid)
			)
			(layer "F.Fab")
		)
		(fp_line
			(start 0.504 0.248)
			(end -0.494 0.248)
			(stroke
				(width 0.15)
				(type solid)
			)
			(layer "F.Fab")
		)
		(fp_line
			(start -0.494 -0.25)
			(end 0.504 -0.25)
			(stroke
				(width 0.15)
				(type solid)
			)
			(layer "F.Fab")
		)
		(fp_line
			(start 0.504 -0.25)
			(end 0.504 0.248)
			(stroke
				(width 0.15)
				(type solid)
			)
			(layer "F.Fab")
		)
		(pad "1" smd roundrect
			(at -0.48 0 270)
			(size 0.59 0.64)
			(layers "F.Cu" "F.Mask" "F.Paste")
			(roundrect_rratio 0.25)
			(net 2 "GND")
			(pintype "passive")
		)
		(pad "2" smd roundrect
			(at 0.48 0 270)
			(size 0.59 0.64)
			(layers "F.Cu" "F.Mask" "F.Paste")
			(roundrect_rratio 0.25)
			(net 12 "Net-(U2-V_{CIN})")
			(pintype "passive")
		)
	)
	(footprint "antmicro-footprints:C_0402_1005Metric"
		(layer "F.Cu")
		(at 100.25 87.6 180)
		(descr "Capacitor SMD 0402")
		(tags "capacitor SMD 0402")
		(property "Reference" "C13"
			(at -0.842 -0.538 0)
			(layer "F.SilkS")
			(effects
				(font
					(size 0.7 0.7)
					(thickness 0.15)
				)
				(justify left bottom)
			)
		)
		(property "Value" "C_270p_25V_0402"
			(at -1.022927 2.155213 0)
			(layer "F.Fab")
			(effects
				(font
					(size 0.7 0.7)
					(thickness 0.15)
				)
				(justify right bottom)
			)
		)
		(property "Datasheet" "https://www.kemet.com/en/us/capacitors/product/C0402C271J3GAC7867.html"
			(at 0 0 180)
			(layer "F.Fab")
			(hide yes)
			(effects
				(font
					(size 1.27 1.27)
					(thickness 0.15)
				)
			)
		)
		(property "Description" "SMD Multilayer Ceramic Capacitor, 270 pF, 25 V, 0402 [1005 Metric], ± 5%, C0G / NP0"
			(at 0 0 180)
			(layer "F.Fab")
			(hide yes)
			(effects
				(font
					(size 1.27 1.27)
					(thickness 0.15)
				)
			)
		)
		(property "Manufacturer" "KEMET"
			(at 0 0 180)
			(unlocked yes)
			(layer "F.Fab")
			(hide yes)
			(effects
				(font
					(size 1 1)
					(thickness 0.15)
				)
			)
		)
		(property "MPN" "C0402C271J3GAC7867"
			(at 0 0 180)
			(unlocked yes)
			(layer "F.Fab")
			(hide yes)
			(effects
				(font
					(size 1 1)
					(thickness 0.15)
				)
			)
		)
		(property "Val" "270p"
			(at 0 0 180)
			(unlocked yes)
			(layer "F.Fab")
			(hide yes)
			(effects
				(font
					(size 1 1)
					(thickness 0.15)
				)
			)
		)
		(property "License" "Apache-2.0"
			(at 0 0 180)
			(unlocked yes)
			(layer "F.Fab")
			(hide yes)
			(effects
				(font
					(size 1 1)
					(thickness 0.15)
				)
			)
		)
		(property "Author" "Antmicro"
			(at 0 0 180)
			(unlocked yes)
			(layer "F.Fab")
			(hide yes)
			(effects
				(font
					(size 1 1)
					(thickness 0.15)
				)
			)
		)
		(property "Voltage" "25V"
			(at 0 0 180)
			(unlocked yes)
			(layer "F.Fab")
			(hide yes)
			(effects
				(font
					(size 1 1)
					(thickness 0.15)
				)
			)
		)
		(property "Dielectric" ""
			(at 0 0 180)
			(unlocked yes)
			(layer "F.Fab")
			(hide yes)
			(effects
				(font
					(size 1 1)
					(thickness 0.15)
				)
			)
		)
		(sheetname "/DC-DC Converters/")
		(sheetfile "dc-dc_converters.kicad_sch")
		(attr smd exclude_from_pos_files exclude_from_bom dnp)
		(fp_rect
			(start -0.925 -0.47)
			(end 0.925 0.47)
			(stroke
				(width 0.05)
				(type default)
			)
			(fill no)
			(layer "F.CrtYd")
		)
		(fp_line
			(start 0.504 0.248)
			(end -0.494 0.248)
			(stroke
				(width 0.15)
				(type solid)
			)
			(layer "F.Fab")
		)
		(fp_line
			(start 0.504 -0.25)
			(end 0.504 0.248)
			(stroke
				(width 0.15)
				(type solid)
			)
			(layer "F.Fab")
		)
		(fp_line
			(start -0.494 0.248)
			(end -0.494 -0.25)
			(stroke
				(width 0.15)
				(type solid)
			)
			(layer "F.Fab")
		)
		(fp_line
			(start -0.494 -0.25)
			(end 0.504 -0.25)
			(stroke
				(width 0.15)
				(type solid)
			)
			(layer "F.Fab")
		)
		(pad "1" smd roundrect
			(at -0.48 0 180)
			(size 0.59 0.64)
			(layers "F.Cu" "F.Mask" "F.Paste")
			(roundrect_rratio 0.25)
			(net 4 "Net-(C13-Pad1)")
			(pintype "passive")
		)
		(pad "2" smd roundrect
			(at 0.48 0 180)
			(size 0.59 0.64)
			(layers "F.Cu" "F.Mask" "F.Paste")
			(roundrect_rratio 0.25)
			(net 2 "GND")
			(pintype "passive")
		)
	)
	(footprint "antmicro-footprints:R_0402_1005Metric"
		(layer "F.Cu")
		(at 99.046136 72.35 90)
		(descr "Resistor SMD 0402")
		(tags "resistor SMD 0402")
		(property "Reference" "R25"
			(at -8.93 -0.570136 0)
			(layer "B.SilkS")
			(effects
				(font
					(size 0.7 0.7)
					(thickness 0.15)
				)
				(justify left bottom mirror)
			)
		)
		(property "Value" "R_470R_0402"
			(at -1.011843 1.772047 90)
			(layer "F.Fab")
			(effects
				(font
					(size 0.7 0.7)
					(thickness 0.15)
				)
				(justify left bottom)
			)
		)
		(property "Datasheet" "https://www.bourns.com/docs/product-datasheets/cr.pdf"
			(at 0 0 90)
			(layer "F.Fab")
			(hide yes)
			(effects
				(font
					(size 1.27 1.27)
					(thickness 0.15)
				)
			)
		)
		(property "Description" "SMD Chip Resistor, 470 ohm, ± 1%, 62.5 mW, 0402 [1005 Metric], Thick Film, General Purpose"
			(at 0 0 90)
			(layer "F.Fab")
			(hide yes)
			(effects
				(font
					(size 1.27 1.27)
					(thickness 0.15)
				)
			)
		)
		(property "MPN" "CR0402-FX-4700GLF"
			(at 0 0 90)
			(unlocked yes)
			(layer "F.Fab")
			(hide yes)
			(effects
				(font
					(size 1 1)
					(thickness 0.15)
				)
			)
		)
		(property "Manufacturer" "Bourns"
			(at 0 0 90)
			(unlocked yes)
			(layer "F.Fab")
			(hide yes)
			(effects
				(font
					(size 1 1)
					(thickness 0.15)
				)
			)
		)
		(property "License" "Apache-2.0"
			(at 0 0 90)
			(unlocked yes)
			(layer "F.Fab")
			(hide yes)
			(effects
				(font
					(size 1 1)
					(thickness 0.15)
				)
			)
		)
		(property "Author" "Antmicro"
			(at 0 0 90)
			(unlocked yes)
			(layer "F.Fab")
			(hide yes)
			(effects
				(font
					(size 1 1)
					(thickness 0.15)
				)
			)
		)
		(property "Val" "470R"
			(at 0 0 90)
			(unlocked yes)
			(layer "F.Fab")
			(hide yes)
			(effects
				(font
					(size 1 1)
					(thickness 0.15)
				)
			)
		)
		(property "Tolerance" "1%"
			(at 0 0 90)
			(unlocked yes)
			(layer "F.Fab")
			(hide yes)
			(effects
				(font
					(size 1 1)
					(thickness 0.15)
				)
			)
		)
		(sheetname "/USB PD/")
		(sheetfile "usb_pd.kicad_sch")
		(attr smd)
		(fp_rect
			(start -0.925 -0.47)
			(end 0.925 0.47)
			(stroke
				(width 0.05)
				(type default)
			)
			(fill no)
			(layer "F.CrtYd")
		)
		(fp_rect
			(start -0.5 -0.25)
			(end 0.5 0.25)
			(stroke
				(width 0.15)
				(type solid)
			)
			(fill no)
			(layer "F.Fab")
		)
		(pad "1" smd roundrect
			(at -0.48 0 90)
			(size 0.59 0.64)
			(layers "F.Cu" "F.Mask" "F.Paste")
			(roundrect_rratio 0.25)
			(net 66 "Net-(D6-A)")
			(pintype "passive")
		)
		(pad "2" smd roundrect
			(at 0.48 0 90)
			(size 0.59 0.64)
			(layers "F.Cu" "F.Mask" "F.Paste")
			(roundrect_rratio 0.25)
			(net 25 "+5V")
			(pintype "passive")
		)
	)
	(footprint "antmicro-footprints:R_0402_1005Metric"
		(layer "F.Cu")
		(at 96.8 80.3 90)
		(descr "Resistor SMD 0402")
		(tags "resistor SMD 0402")
		(property "Reference" "R13"
			(at -2.8849 6.0514 180)
			(layer "B.SilkS")
			(effects
				(font
					(size 0.7 0.7)
					(thickness 0.15)
				)
				(justify left bottom mirror)
			)
		)
		(property "Value" "R_100k_0402"
			(at -1.011843 1.772047 90)
			(layer "F.Fab")
			(effects
				(font
					(size 0.7 0.7)
					(thickness 0.15)
				)
				(justify left bottom)
			)
		)
		(property "Datasheet" "https://www.bourns.com/docs/product-datasheets/cr.pdf"
			(at 0 0 90)
			(layer "F.Fab")
			(hide yes)
			(effects
				(font
					(size 1.27 1.27)
					(thickness 0.15)
				)
			)
		)
		(property "Description" "SMD Chip Resistor, 100 kohm, ± 1%, 62.5 mW, 0402 [1005 Metric], Thick Film, General Purpose"
			(at 0 0 90)
			(layer "F.Fab")
			(hide yes)
			(effects
				(font
					(size 1.27 1.27)
					(thickness 0.15)
				)
			)
		)
		(property "Manufacturer" "Bourns"
			(at 0 0 90)
			(unlocked yes)
			(layer "F.Fab")
			(hide yes)
			(effects
				(font
					(size 1 1)
					(thickness 0.15)
				)
			)
		)
		(property "MPN" "CR0402-FX-1003GLF"
			(at 0 0 90)
			(unlocked yes)
			(layer "F.Fab")
			(hide yes)
			(effects
				(font
					(size 1 1)
					(thickness 0.15)
				)
			)
		)
		(property "Val" "100k"
			(at 0 0 90)
			(unlocked yes)
			(layer "F.Fab")
			(hide yes)
			(effects
				(font
					(size 1 1)
					(thickness 0.15)
				)
			)
		)
		(property "License" "Apache-2.0"
			(at 0 0 90)
			(unlocked yes)
			(layer "F.Fab")
			(hide yes)
			(effects
				(font
					(size 1 1)
					(thickness 0.15)
				)
			)
		)
		(property "Author" "Antmicro"
			(at 0 0 90)
			(unlocked yes)
			(layer "F.Fab")
			(hide yes)
			(effects
				(font
					(size 1 1)
					(thickness 0.15)
				)
			)
		)
		(property "Tolerance" "1%"
			(at 0 0 90)
			(unlocked yes)
			(layer "F.Fab")
			(hide yes)
			(effects
				(font
					(size 1 1)
					(thickness 0.15)
				)
			)
		)
		(sheetname "/DC-DC Converters/")
		(sheetfile "dc-dc_converters.kicad_sch")
		(attr smd)
		(fp_rect
			(start -0.925 -0.47)
			(end 0.925 0.47)
			(stroke
				(width 0.05)
				(type default)
			)
			(fill no)
			(layer "F.CrtYd")
		)
		(fp_rect
			(start -0.5 -0.25)
			(end 0.5 0.25)
			(stroke
				(width 0.15)
				(type solid)
			)
			(fill no)
			(layer "F.Fab")
		)
		(pad "1" smd roundrect
			(at -0.48 0 90)
			(size 0.59 0.64)
			(layers "F.Cu" "F.Mask" "F.Paste")
			(roundrect_rratio 0.25)
			(net 48 "Net-(U2-P_{GOOD})")
			(pintype "passive")
		)
		(pad "2" smd roundrect
			(at 0.48 0 90)
			(size 0.59 0.64)
			(layers "F.Cu" "F.Mask" "F.Paste")
			(roundrect_rratio 0.25)
			(net 10 "/DC-DC Converters/VDD_12V_DCDC")
			(pintype "passive")
		)
	)
	(footprint "antmicro-footprints:TP_SMD_0.75mm"
		(layer "F.Cu")
		(at 86.4 70)
		(property "Reference" "TP2"
			(at -9.184 -5.134 0)
			(layer "F.SilkS")
			(hide yes)
			(effects
				(font
					(size 0.7 0.7)
					(thickness 0.15)
				)
				(justify left bottom)
			)
		)
		(property "Value" "TP_0.75mm_SMD"
			(at 0 1.2 0)
			(layer "F.Fab")
			(effects
				(font
					(size 0.7 0.7)
					(thickness 0.15)
				)
				(justify left bottom)
			)
		)
		(property "Description" "SMT test point"
			(at 0 0 0)
			(layer "F.Fab")
			(hide yes)
			(effects
				(font
					(size 1.27 1.27)
					(thickness 0.15)
				)
			)
		)
		(property "MPN" ""
			(at 0 0 0)
			(unlocked yes)
			(layer "F.Fab")
			(hide yes)
			(effects
				(font
					(size 1 1)
					(thickness 0.15)
				)
			)
		)
		(property "Manufacturer" ""
			(at 0 0 0)
			(unlocked yes)
			(layer "F.Fab")
			(hide yes)
			(effects
				(font
					(size 1 1)
					(thickness 0.15)
				)
			)
		)
		(property "Author" "Antmicro"
			(at 0 0 0)
			(unlocked yes)
			(layer "F.Fab")
			(hide yes)
			(effects
				(font
					(size 1 1)
					(thickness 0.15)
				)
			)
		)
		(property "License" "Apache-2.0"
			(at 0 0 0)
			(unlocked yes)
			(layer "F.Fab")
			(hide yes)
			(effects
				(font
					(size 1 1)
					(thickness 0.15)
				)
			)
		)
		(sheetname "/USB PD/")
		(sheetfile "usb_pd.kicad_sch")
		(attr exclude_from_bom)
		(fp_circle
			(center 0 0)
			(end 0.475 0)
			(stroke
				(width 0.05)
				(type default)
			)
			(fill no)
			(layer "F.CrtYd")
		)
		(pad "1" smd circle
			(at 0 0)
			(size 0.75 0.75)
			(layers "F.Cu" "F.Mask")
			(net 38 "/USB PD/SCL")
			(pinfunction "1")
			(pintype "passive")
		)
	)
	(footprint "antmicro-footprints:C_0805_2012Metric"
		(layer "F.Cu")
		(at 87.4 84.7 90)
		(descr "Capacitor SMD 0805")
		(tags "capacitor SMD 0805")
		(property "Reference" "C16"
			(at -3.69 -4.254 90)
			(layer "F.SilkS")
			(effects
				(font
					(size 0.7 0.7)
					(thickness 0.15)
				)
				(justify left bottom)
			)
		)
		(property "Value" "C_10u_0805_35V"
			(at -2.055717 1.963152 90)
			(layer "F.Fab")
			(effects
				(font
					(size 0.7 0.7)
					(thickness 0.15)
				)
				(justify left bottom)
			)
		)
		(property "Datasheet" "https://www.murata.com/products/productdetail?partno=GRM21BR6YA106KE43%23"
			(at 0 0 90)
			(layer "F.Fab")
			(hide yes)
			(effects
				(font
					(size 1.27 1.27)
					(thickness 0.15)
				)
			)
		)
		(property "Description" "SMD Multilayer Ceramic Capacitor, 10 µF, 35 V, 0805 [2012 Metric], ± 10%, X5R, GRM Series"
			(at 0 0 90)
			(layer "F.Fab")
			(hide yes)
			(effects
				(font
					(size 1.27 1.27)
					(thickness 0.15)
				)
			)
		)
		(property "MPN" "GRM21BR6YA106KE43L"
			(at 0 0 90)
			(unlocked yes)
			(layer "F.Fab")
			(hide yes)
			(effects
				(font
					(size 1 1)
					(thickness 0.15)
				)
			)
		)
		(property "Manufacturer" "Murata"
			(at 0 0 90)
			(unlocked yes)
			(layer "F.Fab")
			(hide yes)
			(effects
				(font
					(size 1 1)
					(thickness 0.15)
				)
			)
		)
		(property "License" "Apache-2.0"
			(at 0 0 90)
			(unlocked yes)
			(layer "F.Fab")
			(hide yes)
			(effects
				(font
					(size 1 1)
					(thickness 0.15)
				)
			)
		)
		(property "Author" "Antmicro"
			(at 0 0 90)
			(unlocked yes)
			(layer "F.Fab")
			(hide yes)
			(effects
				(font
					(size 1 1)
					(thickness 0.15)
				)
			)
		)
		(property "Val" "10u"
			(at 0 0 90)
			(unlocked yes)
			(layer "F.Fab")
			(hide yes)
			(effects
				(font
					(size 1 1)
					(thickness 0.15)
				)
			)
		)
		(property "Voltage" "35V"
			(at 0 0 90)
			(unlocked yes)
			(layer "F.Fab")
			(hide yes)
			(effects
				(font
					(size 1 1)
					(thickness 0.15)
				)
			)
		)
		(property "Dielectric" ""
			(at 0 0 90)
			(unlocked yes)
			(layer "F.Fab")
			(hide yes)
			(effects
				(font
					(size 1 1)
					(thickness 0.15)
				)
			)
		)
		(property "Public" "False"
			(at 0 0 90)
			(unlocked yes)
			(layer "F.Fab")
			(hide yes)
			(effects
				(font
					(size 1 1)
					(thickness 0.15)
				)
			)
		)
		(sheetname "/DC-DC Converters/")
		(sheetfile "dc-dc_converters.kicad_sch")
		(attr smd)
		(fp_line
			(start -0.3 -0.7)
			(end 0.3 -0.7)
			(stroke
				(width 0.15)
				(type solid)
			)
			(layer "F.SilkS")
		)
		(fp_line
			(start -0.3 0.7)
			(end 0.3 0.7)
			(stroke
				(width 0.15)
				(type solid)
			)
			(layer "F.SilkS")
		)
		(fp_rect
			(start 1.95 -0.9)
			(end -1.95 0.9)
			(stroke
				(width 0.05)
				(type default)
			)
			(fill no)
			(layer "F.CrtYd")
		)
		(fp_rect
			(start -0.95 -0.675)
			(end 0.95 0.675)
			(stroke
				(width 0.15)
				(type solid)
			)
			(fill no)
			(layer "F.Fab")
		)
		(pad "1" smd roundrect
			(at -1.1 0 90)
			(size 1.2 1.3)
			(layers "F.Cu" "F.Mask" "F.Paste")
			(roundrect_rratio 0.25)
			(net 2 "GND")
			(pintype "passive")
		)
		(pad "2" smd roundrect
			(at 1.1 0 90)
			(size 1.2 1.3)
			(layers "F.Cu" "F.Mask" "F.Paste")
			(roundrect_rratio 0.25)
			(net 12 "Net-(U2-V_{CIN})")
			(pintype "passive")
		)
	)
	(footprint "antmicro-footprints:TP_SMD_0.75mm"
		(layer "F.Cu")
		(at 87.4 70)
		(property "Reference" "TP1"
			(at 7.342 -2.086 0)
			(layer "F.SilkS")
			(hide yes)
			(effects
				(font
					(size 0.7 0.7)
					(thickness 0.15)
				)
				(justify left bottom)
			)
		)
		(property "Value" "TP_0.75mm_SMD"
			(at 0 1.2 0)
			(layer "F.Fab")
			(effects
				(font
					(size 0.7 0.7)
					(thickness 0.15)
				)
				(justify left bottom)
			)
		)
		(property "Description" "SMT test point"
			(at 0 0 0)
			(layer "F.Fab")
			(hide yes)
			(effects
				(font
					(size 1.27 1.27)
					(thickness 0.15)
				)
			)
		)
		(property "MPN" ""
			(at 0 0 0)
			(unlocked yes)
			(layer "F.Fab")
			(hide yes)
			(effects
				(font
					(size 1 1)
					(thickness 0.15)
				)
			)
		)
		(property "Manufacturer" ""
			(at 0 0 0)
			(unlocked yes)
			(layer "F.Fab")
			(hide yes)
			(effects
				(font
					(size 1 1)
					(thickness 0.15)
				)
			)
		)
		(property "Author" "Antmicro"
			(at 0 0 0)
			(unlocked yes)
			(layer "F.Fab")
			(hide yes)
			(effects
				(font
					(size 1 1)
					(thickness 0.15)
				)
			)
		)
		(property "License" "Apache-2.0"
			(at 0 0 0)
			(unlocked yes)
			(layer "F.Fab")
			(hide yes)
			(effects
				(font
					(size 1 1)
					(thickness 0.15)
				)
			)
		)
		(sheetname "/USB PD/")
		(sheetfile "usb_pd.kicad_sch")
		(attr exclude_from_bom)
		(fp_circle
			(center 0 0)
			(end 0.475 0)
			(stroke
				(width 0.05)
				(type default)
			)
			(fill no)
			(layer "F.CrtYd")
		)
		(pad "1" smd circle
			(at 0 0)
			(size 0.75 0.75)
			(layers "F.Cu" "F.Mask")
			(net 37 "/USB PD/SDA")
			(pinfunction "1")
			(pintype "passive")
		)
	)
	(footprint "antmicro-footprints:D_SOD-323F"
		(layer "F.Cu")
		(at 91.9 72.1 180)
		(property "Reference" "D1"
			(at -1.2 2.7 0)
			(layer "F.SilkS")
			(effects
				(font
					(size 0.7 0.7)
					(thickness 0.15)
				)
				(justify right bottom)
			)
		)
		(property "Value" "PMEG6002EJ,115"
			(at -1.7 1.899 0)
			(layer "F.Fab")
			(effects
				(font
					(size 0.7 0.7)
					(thickness 0.15)
				)
				(justify right bottom)
			)
		)
		(property "Datasheet" "https://assets.nexperia.com/documents/data-sheet/PMEG6002EJ.pdf"
			(at 0 0 180)
			(layer "F.Fab")
			(hide yes)
			(effects
				(font
					(size 1.27 1.27)
					(thickness 0.15)
				)
			)
		)
		(property "Description" "Schottky Rectifier, Low VF, 60 V, 200 mA, Single, SOD-323F, 2 Pins, 600 mV"
			(at 0 0 180)
			(layer "F.Fab")
			(hide yes)
			(effects
				(font
					(size 1.27 1.27)
					(thickness 0.15)
				)
			)
		)
		(property "MPN" "PMEG6002EJ,115"
			(at 0 0 180)
			(unlocked yes)
			(layer "F.Fab")
			(hide yes)
			(effects
				(font
					(size 1 1)
					(thickness 0.15)
				)
			)
		)
		(property "Manufacturer" "Nexperia"
			(at 0 0 180)
			(unlocked yes)
			(layer "F.Fab")
			(hide yes)
			(effects
				(font
					(size 1 1)
					(thickness 0.15)
				)
			)
		)
		(property "Author" "Antmicro"
			(at 0 0 180)
			(unlocked yes)
			(layer "F.Fab")
			(hide yes)
			(effects
				(font
					(size 1 1)
					(thickness 0.15)
				)
			)
		)
		(property "License" "Apache-2.0"
			(at 0 0 180)
			(unlocked yes)
			(layer "F.Fab")
			(hide yes)
			(effects
				(font
					(size 1 1)
					(thickness 0.15)
				)
			)
		)
		(sheetname "/USB PD/")
		(sheetfile "usb_pd.kicad_sch")
		(attr smd)
		(fp_line
			(start 0.973 0.749)
			(end 0.623 0.749)
			(stroke
				(width 0.15)
				(type solid)
			)
			(layer "F.SilkS")
		)
		(fp_line
			(start 0.973 0.451)
			(end 0.973 0.749)
			(stroke
				(width 0.15)
				(type solid)
			)
			(layer "F.SilkS")
		)
		(fp_line
			(start 0.973 -0.749)
			(end 0.973 -0.449)
			(stroke
				(width 0.15)
				(type solid)
			)
			(layer "F.SilkS")
		)
		(fp_line
			(start 0.623 -0.749)
			(end 0.973 -0.749)
			(stroke
				(width 0.15)
				(type solid)
			)
			(layer "F.SilkS")
		)
		(fp_line
			(start -0.5 -0.425)
			(end -0.5 0.425)
			(stroke
				(width 0.15)
				(type solid)
			)
			(layer "F.SilkS")
		)
		(fp_line
			(start -0.625 0.749)
			(end -0.975 0.749)
			(stroke
				(width 0.15)
				(type solid)
			)
			(layer "F.SilkS")
		)
		(fp_line
			(start -0.625 -0.749)
			(end -0.975 -0.749)
			(stroke
				(width 0.15)
				(type solid)
			)
			(layer "F.SilkS")
		)
		(fp_line
			(start -0.975 0.749)
			(end -0.975 0.451)
			(stroke
				(width 0.15)
				(type solid)
			)
			(layer "F.SilkS")
		)
		(fp_line
			(start -0.975 -0.749)
			(end -0.975 -0.449)
			(stroke
				(width 0.15)
				(type solid)
			)
			(layer "F.SilkS")
		)
		(fp_rect
			(start -1.55 -0.95)
			(end 1.55 0.95)
			(stroke
				(width 0.05)
				(type solid)
			)
			(fill no)
			(layer "F.CrtYd")
		)
		(fp_rect
			(start -1.25 -0.676)
			(end 1.245365 0.676)
			(stroke
				(width 0.1)
				(type solid)
			)
			(fill no)
			(layer "F.Fab")
		)
		(pad "1" smd roundrect
			(at -1.051 0.001 180)
			(size 0.8 0.6)
			(layers "F.Cu" "F.Mask" "F.Paste")
			(roundrect_rratio 0.15)
			(net 63 "Net-(D1-C)")
			(pinfunction "C")
			(pintype "passive")
		)
		(pad "2" smd roundrect
			(at 1.05 0.001 180)
			(size 0.8 0.6)
			(layers "F.Cu" "F.Mask" "F.Paste")
			(roundrect_rratio 0.15)
			(net 6 "VBUS")
			(pinfunction "A")
			(pintype "passive")
		)
	)
	(footprint "antmicro-footprints:R_0402_1005Metric"
		(layer "F.Cu")
		(at 84.176 77.575)
		(descr "Resistor SMD 0402")
		(tags "resistor SMD 0402")
		(property "Reference" "R22"
			(at -1.239 2.202 180)
			(layer "F.SilkS")
			(effects
				(font
					(size 0.7 0.7)
					(thickness 0.15)
				)
				(justify left bottom)
			)
		)
		(property "Value" "R_22k_0402"
			(at -1.011843 1.772047 0)
			(layer "F.Fab")
			(effects
				(font
					(size 0.7 0.7)
					(thickness 0.15)
				)
				(justify left bottom)
			)
		)
		(property "Datasheet" "https://www.bourns.com/docs/product-datasheets/cr.pdf"
			(at 0 0 0)
			(layer "F.Fab")
			(hide yes)
			(effects
				(font
					(size 1.27 1.27)
					(thickness 0.15)
				)
			)
		)
		(property "Description" "SMD Chip Resistor, 22 kohm, ± 1%, 62.5 mW, 0402 [1005 Metric], Thick Film, General Purpose"
			(at 0 0 0)
			(layer "F.Fab")
			(hide yes)
			(effects
				(font
					(size 1.27 1.27)
					(thickness 0.15)
				)
			)
		)
		(property "MPN" "CR0402-FX-2202GLF"
			(at 0 0 0)
			(unlocked yes)
			(layer "F.Fab")
			(hide yes)
			(effects
				(font
					(size 1 1)
					(thickness 0.15)
				)
			)
		)
		(property "Manufacturer" "Bourns"
			(at 0 0 0)
			(unlocked yes)
			(layer "F.Fab")
			(hide yes)
			(effects
				(font
					(size 1 1)
					(thickness 0.15)
				)
			)
		)
		(property "License" "Apache-2.0"
			(at 0 0 0)
			(unlocked yes)
			(layer "F.Fab")
			(hide yes)
			(effects
				(font
					(size 1 1)
					(thickness 0.15)
				)
			)
		)
		(property "Author" "Antmicro"
			(at 0 0 0)
			(unlocked yes)
			(layer "F.Fab")
			(hide yes)
			(effects
				(font
					(size 1 1)
					(thickness 0.15)
				)
			)
		)
		(property "Val" "22k"
			(at 0 0 0)
			(unlocked yes)
			(layer "F.Fab")
			(hide yes)
			(effects
				(font
					(size 1 1)
					(thickness 0.15)
				)
			)
		)
		(property "Tolerance" "1%"
			(at 0 0 0)
			(unlocked yes)
			(layer "F.Fab")
			(hide yes)
			(effects
				(font
					(size 1 1)
					(thickness 0.15)
				)
			)
		)
		(sheetname "/USB PD/")
		(sheetfile "usb_pd.kicad_sch")
		(attr smd)
		(fp_rect
			(start -0.925 -0.47)
			(end 0.925 0.47)
			(stroke
				(width 0.05)
				(type default)
			)
			(fill no)
			(layer "F.CrtYd")
		)
		(fp_rect
			(start -0.5 -0.25)
			(end 0.5 0.25)
			(stroke
				(width 0.15)
				(type solid)
			)
			(fill no)
			(layer "F.Fab")
		)
		(pad "1" smd roundrect
			(at -0.48 0)
			(size 0.59 0.64)
			(layers "F.Cu" "F.Mask" "F.Paste")
			(roundrect_rratio 0.25)
			(net 53 "/USB PD/VBUS_EN")
			(pintype "passive")
		)
		(pad "2" smd roundrect
			(at 0.48 0)
			(size 0.59 0.64)
			(layers "F.Cu" "F.Mask" "F.Paste")
			(roundrect_rratio 0.25)
			(net 7 "Net-(Q1-G)")
			(pintype "passive")
		)
	)
	(footprint "antmicro-footprints:C_0805_2012Metric"
		(layer "F.Cu")
		(at 95.401 72.25 180)
		(descr "Capacitor SMD 0805")
		(tags "capacitor SMD 0805")
		(property "Reference" "C7"
			(at -1.5 -11.5 0)
			(layer "B.SilkS")
			(effects
				(font
					(size 0.7 0.7)
					(thickness 0.15)
				)
				(justify right bottom mirror)
			)
		)
		(property "Value" "C_10u_0805_35V"
			(at -2.055717 1.963152 0)
			(layer "F.Fab")
			(effects
				(font
					(size 0.7 0.7)
					(thickness 0.15)
				)
				(justify right bottom)
			)
		)
		(property "Datasheet" "https://www.murata.com/products/productdetail?partno=GRM21BR6YA106KE43%23"
			(at 0 0 180)
			(layer "F.Fab")
			(hide yes)
			(effects
				(font
					(size 1.27 1.27)
					(thickness 0.15)
				)
			)
		)
		(property "Description" "SMD Multilayer Ceramic Capacitor, 10 µF, 35 V, 0805 [2012 Metric], ± 10%, X5R, GRM Series"
			(at 0 0 180)
			(layer "F.Fab")
			(hide yes)
			(effects
				(font
					(size 1.27 1.27)
					(thickness 0.15)
				)
			)
		)
		(property "MPN" "GRM21BR6YA106KE43L"
			(at 0 0 180)
			(unlocked yes)
			(layer "F.Fab")
			(hide yes)
			(effects
				(font
					(size 1 1)
					(thickness 0.15)
				)
			)
		)
		(property "Manufacturer" "Murata"
			(at 0 0 180)
			(unlocked yes)
			(layer "F.Fab")
			(hide yes)
			(effects
				(font
					(size 1 1)
					(thickness 0.15)
				)
			)
		)
		(property "License" "Apache-2.0"
			(at 0 0 180)
			(unlocked yes)
			(layer "F.Fab")
			(hide yes)
			(effects
				(font
					(size 1 1)
					(thickness 0.15)
				)
			)
		)
		(property "Author" "Antmicro"
			(at 0 0 180)
			(unlocked yes)
			(layer "F.Fab")
			(hide yes)
			(effects
				(font
					(size 1 1)
					(thickness 0.15)
				)
			)
		)
		(property "Val" "10u"
			(at 0 0 180)
			(unlocked yes)
			(layer "F.Fab")
			(hide yes)
			(effects
				(font
					(size 1 1)
					(thickness 0.15)
				)
			)
		)
		(property "Voltage" "35V"
			(at 0 0 180)
			(unlocked yes)
			(layer "F.Fab")
			(hide yes)
			(effects
				(font
					(size 1 1)
					(thickness 0.15)
				)
			)
		)
		(property "Dielectric" ""
			(at 0 0 180)
			(unlocked yes)
			(layer "F.Fab")
			(hide yes)
			(effects
				(font
					(size 1 1)
					(thickness 0.15)
				)
			)
		)
		(property "Public" "False"
			(at 0 0 180)
			(unlocked yes)
			(layer "F.Fab")
			(hide yes)
			(effects
				(font
					(size 1 1)
					(thickness 0.15)
				)
			)
		)
		(sheetname "/USB PD/")
		(sheetfile "usb_pd.kicad_sch")
		(attr smd)
		(fp_line
			(start -0.3 0.7)
			(end 0.3 0.7)
			(stroke
				(width 0.15)
				(type solid)
			)
			(layer "F.SilkS")
		)
		(fp_line
			(start -0.3 -0.7)
			(end 0.3 -0.7)
			(stroke
				(width 0.15)
				(type solid)
			)
			(layer "F.SilkS")
		)
		(fp_rect
			(start 1.95 -0.9)
			(end -1.95 0.9)
			(stroke
				(width 0.05)
				(type default)
			)
			(fill no)
			(layer "F.CrtYd")
		)
		(fp_rect
			(start -0.95 -0.675)
			(end 0.95 0.675)
			(stroke
				(width 0.15)
				(type solid)
			)
			(fill no)
			(layer "F.Fab")
		)
		(pad "1" smd roundrect
			(at -1.1 0 180)
			(size 1.2 1.3)
			(layers "F.Cu" "F.Mask" "F.Paste")
			(roundrect_rratio 0.25)
			(net 2 "GND")
			(pintype "passive")
		)
		(pad "2" smd roundrect
			(at 1.1 0 180)
			(size 1.2 1.3)
			(layers "F.Cu" "F.Mask" "F.Paste")
			(roundrect_rratio 0.25)
			(net 63 "Net-(D1-C)")
			(pintype "passive")
		)
	)
	(footprint "antmicro-footprints:C_0402_1005Metric"
		(layer "F.Cu")
		(at 89.4 71.7 180)
		(descr "Capacitor SMD 0402")
		(tags "capacitor SMD 0402")
		(property "Reference" "C11"
			(at -4.41 0.35 90)
			(layer "B.SilkS")
			(effects
				(font
					(size 0.7 0.7)
					(thickness 0.15)
				)
				(justify left bottom mirror)
			)
		)
		(property "Value" "C_1u_25V_0402"
			(at -1.022927 2.155213 0)
			(layer "F.Fab")
			(effects
				(font
					(size 0.7 0.7)
					(thickness 0.15)
				)
				(justify right bottom)
			)
		)
		(property "Datasheet" "https://www.murata.com/products/productdetail?partno=GRM155R61E105KE11%23"
			(at 0 0 180)
			(layer "F.Fab")
			(hide yes)
			(effects
				(font
					(size 1.27 1.27)
					(thickness 0.15)
				)
			)
		)
		(property "Description" "SMD Multilayer Ceramic Capacitor, 1 µF, 25 V, 0402 [1005 Metric], ± 10%, X5R, GRM Series"
			(at 0 0 180)
			(layer "F.Fab")
			(hide yes)
			(effects
				(font
					(size 1.27 1.27)
					(thickness 0.15)
				)
			)
		)
		(property "MPN" "GRM155R61E105KE11J"
			(at 0 0 180)
			(unlocked yes)
			(layer "F.Fab")
			(hide yes)
			(effects
				(font
					(size 1 1)
					(thickness 0.15)
				)
			)
		)
		(property "Manufacturer" "Murata"
			(at 0 0 180)
			(unlocked yes)
			(layer "F.Fab")
			(hide yes)
			(effects
				(font
					(size 1 1)
					(thickness 0.15)
				)
			)
		)
		(property "License" "Apache-2.0"
			(at 0 0 180)
			(unlocked yes)
			(layer "F.Fab")
			(hide yes)
			(effects
				(font
					(size 1 1)
					(thickness 0.15)
				)
			)
		)
		(property "Author" "Antmicro"
			(at 0 0 180)
			(unlocked yes)
			(layer "F.Fab")
			(hide yes)
			(effects
				(font
					(size 1 1)
					(thickness 0.15)
				)
			)
		)
		(property "Val" "1u"
			(at 0 0 180)
			(unlocked yes)
			(layer "F.Fab")
			(hide yes)
			(effects
				(font
					(size 1 1)
					(thickness 0.15)
				)
			)
		)
		(property "Voltage" "25V"
			(at 0 0 180)
			(unlocked yes)
			(layer "F.Fab")
			(hide yes)
			(effects
				(font
					(size 1 1)
					(thickness 0.15)
				)
			)
		)
		(property "Dielectric" "X5R"
			(at 0 0 180)
			(unlocked yes)
			(layer "F.Fab")
			(hide yes)
			(effects
				(font
					(size 1 1)
					(thickness 0.15)
				)
			)
		)
		(sheetname "/USB PD/")
		(sheetfile "usb_pd.kicad_sch")
		(attr smd)
		(fp_rect
			(start -0.925 -0.47)
			(end 0.925 0.47)
			(stroke
				(width 0.05)
				(type default)
			)
			(fill no)
			(layer "F.CrtYd")
		)
		(fp_line
			(start 0.504 0.248)
			(end -0.494 0.248)
			(stroke
				(width 0.15)
				(type solid)
			)
			(layer "F.Fab")
		)
		(fp_line
			(start 0.504 -0.25)
			(end 0.504 0.248)
			(stroke
				(width 0.15)
				(type solid)
			)
			(layer "F.Fab")
		)
		(fp_line
			(start -0.494 0.248)
			(end -0.494 -0.25)
			(stroke
				(width 0.15)
				(type solid)
			)
			(layer "F.Fab")
		)
		(fp_line
			(start -0.494 -0.25)
			(end 0.504 -0.25)
			(stroke
				(width 0.15)
				(type solid)
			)
			(layer "F.Fab")
		)
		(pad "1" smd roundrect
			(at -0.48 0 180)
			(size 0.59 0.64)
			(layers "F.Cu" "F.Mask" "F.Paste")
			(roundrect_rratio 0.25)
			(net 2 "GND")
			(pintype "passive")
		)
		(pad "2" smd roundrect
			(at 0.48 0 180)
			(size 0.59 0.64)
			(layers "F.Cu" "F.Mask" "F.Paste")
			(roundrect_rratio 0.25)
			(net 6 "VBUS")
			(pintype "passive")
		)
	)
	(footprint "antmicro-footprints:L_Abracon_ASPIAIG-Q8080"
		(layer "F.Cu")
		(at 98.3 95.425 -90)
		(property "Reference" "L1"
			(at -5.025 5.9 0)
			(unlocked yes)
			(layer "F.SilkS")
			(effects
				(font
					(size 0.7 0.7)
					(thickness 0.15)
				)
				(justify left bottom)
			)
		)
		(property "Value" "L_4u7_14.6A_Abracon-Q8080"
			(at 0 10.16 270)
			(unlocked yes)
			(layer "F.Fab")
			(effects
				(font
					(size 0.7 0.7)
					(thickness 0.15)
				)
				(justify left bottom)
			)
		)
		(property "Datasheet" "https://www.mouser.com/datasheet/2/3/ASPIAIG_Q8080-2256550.pdf"
			(at 0 0 270)
			(layer "F.Fab")
			(hide yes)
			(effects
				(font
					(size 1.27 1.27)
					(thickness 0.15)
				)
			)
		)
		(property "Description" "Power Inductors - SMD 4.7 UH 20%"
			(at 0 0 270)
			(layer "F.Fab")
			(hide yes)
			(effects
				(font
					(size 1.27 1.27)
					(thickness 0.15)
				)
			)
		)
		(property "MPN" "ASPIAIG-Q8080-4R7M-T"
			(at 0 0 270)
			(unlocked yes)
			(layer "F.Fab")
			(hide yes)
			(effects
				(font
					(size 1 1)
					(thickness 0.15)
				)
			)
		)
		(property "ISat" "17A"
			(at 0 0 270)
			(unlocked yes)
			(layer "F.Fab")
			(hide yes)
			(effects
				(font
					(size 1 1)
					(thickness 0.15)
				)
			)
		)
		(property "IMax" "14.6A"
			(at 0 0 270)
			(unlocked yes)
			(layer "F.Fab")
			(hide yes)
			(effects
				(font
					(size 1 1)
					(thickness 0.15)
				)
			)
		)
		(property "Size" "8.9x8.5"
			(at 0 0 270)
			(unlocked yes)
			(layer "F.Fab")
			(hide yes)
			(effects
				(font
					(size 1 1)
					(thickness 0.15)
				)
			)
		)
		(property "Val" "4.7u/14.6A"
			(at 0 0 270)
			(unlocked yes)
			(layer "F.Fab")
			(hide yes)
			(effects
				(font
					(size 1 1)
					(thickness 0.15)
				)
			)
		)
		(property "Author" "Antmicro"
			(at 0 0 270)
			(unlocked yes)
			(layer "F.Fab")
			(hide yes)
			(effects
				(font
					(size 1 1)
					(thickness 0.15)
				)
			)
		)
		(property "License" "Apache-2.0"
			(at 0 0 270)
			(unlocked yes)
			(layer "F.Fab")
			(hide yes)
			(effects
				(font
					(size 1 1)
					(thickness 0.15)
				)
			)
		)
		(property "Manufacturer" "Abracon"
			(at 0 0 270)
			(unlocked yes)
			(layer "F.Fab")
			(hide yes)
			(effects
				(font
					(size 1 1)
					(thickness 0.15)
				)
			)
		)
		(sheetname "/DC-DC Converters/")
		(sheetfile "dc-dc_converters.kicad_sch")
		(attr smd)
		(fp_rect
			(start -4.6 -4.4)
			(end 4.6 4.4)
			(stroke
				(width 0.15)
				(type default)
			)
			(fill no)
			(layer "F.SilkS")
		)
		(fp_rect
			(start -4.85 -4.64)
			(end 4.85 4.64)
			(stroke
				(width 0.05)
				(type solid)
			)
			(fill no)
			(layer "F.CrtYd")
		)
		(fp_rect
			(start -4.597 -4.394)
			(end 4.597 4.394)
			(stroke
				(width 0.15)
				(type default)
			)
			(fill no)
			(layer "F.Fab")
		)
		(pad "1" smd roundrect
			(at -2.675 0 270)
			(size 2.65 7.8)
			(layers "F.Cu" "F.Mask" "F.Paste")
			(roundrect_rratio 0.05)
			(net 8 "Net-(L1-Pad1)")
			(pintype "passive")
		)
		(pad "2" smd roundrect
			(at 2.675 0 270)
			(size 2.65 7.8)
			(layers "F.Cu" "F.Mask" "F.Paste")
			(roundrect_rratio 0.05)
			(net 5 "+12V")
			(pintype "passive")
		)
	)
	(footprint "antmicro-footprints:Vishay_PowerPAK_1212-8_Single"
		(layer "F.Cu")
		(at 88.8 78.65 -90)
		(descr "PowerPAK 1212-8 Single")
		(tags "Vishay PowerPAK 1212-8 Single")
		(property "Reference" "Q1"
			(at 0.19 -5.236 180)
			(layer "F.SilkS")
			(effects
				(font
					(size 0.7 0.7)
					(thickness 0.15)
				)
				(justify right bottom)
			)
		)
		(property "Value" "SQS401EN-T1_BE3"
			(at 0 2.7 90)
			(layer "F.Fab")
			(effects
				(font
					(size 0.7 0.7)
					(thickness 0.15)
				)
				(justify right bottom)
			)
		)
		(property "Datasheet" "https://www.vishay.com/docs/65529/sqs401en.pdf"
			(at 0 0 270)
			(layer "F.Fab")
			(hide yes)
			(effects
				(font
					(size 1.27 1.27)
					(thickness 0.15)
				)
			)
		)
		(property "Description" "MOSFET, P Channel, 40 V, 16A, 0.047 ohm, PowerPAK 1212-8, Surface Mount"
			(at 0 0 270)
			(layer "F.Fab")
			(hide yes)
			(effects
				(font
					(size 1.27 1.27)
					(thickness 0.15)
				)
			)
		)
		(property "MPN" "SQS401EN-T1_BE3"
			(at 0 0 270)
			(unlocked yes)
			(layer "F.Fab")
			(hide yes)
			(effects
				(font
					(size 1 1)
					(thickness 0.15)
				)
			)
		)
		(property "Manufacturer" "Vishay"
			(at 0 0 270)
			(unlocked yes)
			(layer "F.Fab")
			(hide yes)
			(effects
				(font
					(size 1 1)
					(thickness 0.15)
				)
			)
		)
		(property "Author" "Antmicro"
			(at 0 0 270)
			(unlocked yes)
			(layer "F.Fab")
			(hide yes)
			(effects
				(font
					(size 1 1)
					(thickness 0.15)
				)
			)
		)
		(property "License" "Apache-2.0"
			(at 0 0 270)
			(unlocked yes)
			(layer "F.Fab")
			(hide yes)
			(effects
				(font
					(size 1 1)
					(thickness 0.15)
				)
			)
		)
		(sheetname "/USB PD/")
		(sheetfile "usb_pd.kicad_sch")
		(attr smd)
		(fp_line
			(start -1.635 1.634)
			(end 1.634 1.634)
			(stroke
				(width 0.15)
				(type solid)
			)
			(layer "F.SilkS")
		)
		(fp_line
			(start -1.635 1.3)
			(end -1.635 1.634)
			(stroke
				(width 0.15)
				(type solid)
			)
			(layer "F.SilkS")
		)
		(fp_line
			(start 1.634 1.3)
			(end 1.634 1.634)
			(stroke
				(width 0.15)
				(type solid)
			)
			(layer "F.SilkS")
		)
		(fp_line
			(start -1.651 -1.651)
			(end -1.651 -1.317)
			(stroke
				(width 0.15)
				(type solid)
			)
			(layer "F.SilkS")
		)
		(fp_line
			(start -1.651 -1.651)
			(end 1.648 -1.651)
			(stroke
				(width 0.15)
				(type solid)
			)
			(layer "F.SilkS")
		)
		(fp_line
			(start 1.648 -1.651)
			(end 1.648 -1.317)
			(stroke
				(width 0.15)
				(type solid)
			)
			(layer "F.SilkS")
		)
		(fp_circle
			(center -1.9 -1.4)
			(end -1.85 -1.4)
			(stroke
				(width 0.15)
				(type solid)
			)
			(fill yes)
			(layer "F.SilkS")
		)
		(fp_rect
			(start -2 -1.8)
			(end 2 1.798)
			(stroke
				(width 0.05)
				(type solid)
			)
			(fill no)
			(layer "F.CrtYd")
		)
		(fp_line
			(start -1.6425 -1.4175)
			(end -1.4175 -1.6425)
			(stroke
				(width 0.15)
				(type solid)
			)
			(layer "F.Fab")
		)
		(fp_rect
			(start -1.651 -1.651)
			(end 1.648 1.648)
			(stroke
				(width 0.15)
				(type solid)
			)
			(fill no)
			(layer "F.Fab")
		)
		(pad "1" smd rect
			(at -1.436 -0.99 270)
			(size 0.99 0.405)
			(layers "F.Cu" "F.Mask" "F.Paste")
			(net 6 "VBUS")
			(pinfunction "S")
			(pintype "passive")
		)
		(pad "2" smd rect
			(at -1.436 -0.332 270)
			(size 0.99 0.405)
			(layers "F.Cu" "F.Mask" "F.Paste")
			(net 6 "VBUS")
			(pinfunction "S")
			(pintype "passive")
		)
		(pad "3" smd rect
			(at -1.436 0.33 270)
			(size 0.99 0.405)
			(layers "F.Cu" "F.Mask" "F.Paste")
			(net 6 "VBUS")
			(pinfunction "S")
			(pintype "passive")
		)
		(pad "4" smd rect
			(at -1.436 0.988 270)
			(size 0.99 0.405)
			(layers "F.Cu" "F.Mask" "F.Paste")
			(net 7 "Net-(Q1-G)")
			(pinfunction "G")
			(pintype "input")
		)
		(pad "5" smd custom
			(at 0.557 0 270)
			(size 1.725 2.235)
			(layers "F.Cu" "F.Mask" "F.Paste")
			(net 3 "VCC")
			(pinfunction "D")
			(pintype "passive")
			(zone_connect 2)
			(options
				(clearance outline)
				(anchor rect)
			)
			(primitives
				(gr_poly
					(pts
						(xy 0.8625 0.1275) (xy 0.8625 -0.1275) (xy 1.3725 -0.1275) (xy 1.3725 -0.5325) (xy 0.8625 -0.5325)
						(xy 0.8625 -0.7875) (xy 1.3725 -0.7875) (xy 1.3725 -1.195) (xy 0.6125 -1.195) (xy 0.6125 1.195)
						(xy 1.3725 1.195) (xy 1.3725 0.7875) (xy 0.8625 0.7875) (xy 0.8625 0.5325) (xy 1.3725 0.5325)
						(xy 1.3725 0.1275)
					)
					(width 0)
					(fill yes)
				)
			)
		)
	)
	(footprint "antmicro-footprints:C_0402_1005Metric"
		(layer "F.Cu")
		(at 89.4 72.7 180)
		(descr "Capacitor SMD 0402")
		(tags "capacitor SMD 0402")
		(property "Reference" "C8"
			(at -5.426 1.35 90)
			(layer "B.SilkS")
			(effects
				(font
					(size 0.7 0.7)
					(thickness 0.15)
				)
				(justify left bottom mirror)
			)
		)
		(property "Value" "C_1u_25V_0402"
			(at -1.022927 2.155213 0)
			(layer "F.Fab")
			(effects
				(font
					(size 0.7 0.7)
					(thickness 0.15)
				)
				(justify right bottom)
			)
		)
		(property "Datasheet" "https://www.murata.com/products/productdetail?partno=GRM155R61E105KE11%23"
			(at 0 0 180)
			(layer "F.Fab")
			(hide yes)
			(effects
				(font
					(size 1.27 1.27)
					(thickness 0.15)
				)
			)
		)
		(property "Description" "SMD Multilayer Ceramic Capacitor, 1 µF, 25 V, 0402 [1005 Metric], ± 10%, X5R, GRM Series"
			(at 0 0 180)
			(layer "F.Fab")
			(hide yes)
			(effects
				(font
					(size 1.27 1.27)
					(thickness 0.15)
				)
			)
		)
		(property "MPN" "GRM155R61E105KE11J"
			(at 0 0 180)
			(unlocked yes)
			(layer "F.Fab")
			(hide yes)
			(effects
				(font
					(size 1 1)
					(thickness 0.15)
				)
			)
		)
		(property "Manufacturer" "Murata"
			(at 0 0 180)
			(unlocked yes)
			(layer "F.Fab")
			(hide yes)
			(effects
				(font
					(size 1 1)
					(thickness 0.15)
				)
			)
		)
		(property "License" "Apache-2.0"
			(at 0 0 180)
			(unlocked yes)
			(layer "F.Fab")
			(hide yes)
			(effects
				(font
					(size 1 1)
					(thickness 0.15)
				)
			)
		)
		(property "Author" "Antmicro"
			(at 0 0 180)
			(unlocked yes)
			(layer "F.Fab")
			(hide yes)
			(effects
				(font
					(size 1 1)
					(thickness 0.15)
				)
			)
		)
		(property "Val" "1u"
			(at 0 0 180)
			(unlocked yes)
			(layer "F.Fab")
			(hide yes)
			(effects
				(font
					(size 1 1)
					(thickness 0.15)
				)
			)
		)
		(property "Voltage" "25V"
			(at 0 0 180)
			(unlocked yes)
			(layer "F.Fab")
			(hide yes)
			(effects
				(font
					(size 1 1)
					(thickness 0.15)
				)
			)
		)
		(property "Dielectric" "X5R"
			(at 0 0 180)
			(unlocked yes)
			(layer "F.Fab")
			(hide yes)
			(effects
				(font
					(size 1 1)
					(thickness 0.15)
				)
			)
		)
		(sheetname "/USB PD/")
		(sheetfile "usb_pd.kicad_sch")
		(attr smd)
		(fp_rect
			(start -0.925 -0.47)
			(end 0.925 0.47)
			(stroke
				(width 0.05)
				(type default)
			)
			(fill no)
			(layer "F.CrtYd")
		)
		(fp_line
			(start 0.504 0.248)
			(end -0.494 0.248)
			(stroke
				(width 0.15)
				(type solid)
			)
			(layer "F.Fab")
		)
		(fp_line
			(start 0.504 -0.25)
			(end 0.504 0.248)
			(stroke
				(width 0.15)
				(type solid)
			)
			(layer "F.Fab")
		)
		(fp_line
			(start -0.494 0.248)
			(end -0.494 -0.25)
			(stroke
				(width 0.15)
				(type solid)
			)
			(layer "F.Fab")
		)
		(fp_line
			(start -0.494 -0.25)
			(end 0.504 -0.25)
			(stroke
				(width 0.15)
				(type solid)
			)
			(layer "F.Fab")
		)
		(pad "1" smd roundrect
			(at -0.48 0 180)
			(size 0.59 0.64)
			(layers "F.Cu" "F.Mask" "F.Paste")
			(roundrect_rratio 0.25)
			(net 2 "GND")
			(pintype "passive")
		)
		(pad "2" smd roundrect
			(at 0.48 0 180)
			(size 0.59 0.64)
			(layers "F.Cu" "F.Mask" "F.Paste")
			(roundrect_rratio 0.25)
			(net 14 "Net-(U1-VREG_2V7)")
			(pintype "passive")
		)
	)
	(footprint "antmicro-footprints:R_0402_1005Metric"
		(layer "F.Cu")
		(at 102.576 72.35 90)
		(descr "Resistor SMD 0402")
		(tags "resistor SMD 0402")
		(property "Reference" "R30"
			(at -5.862 -4.102 0)
			(layer "B.SilkS")
			(effects
				(font
					(size 0.7 0.7)
					(thickness 0.15)
				)
				(justify left bottom mirror)
			)
		)
		(property "Value" "R_220R_0402"
			(at -1.011843 1.772047 90)
			(layer "F.Fab")
			(effects
				(font
					(size 0.7 0.7)
					(thickness 0.15)
				)
				(justify left bottom)
			)
		)
		(property "Datasheet" "https://www.bourns.com/docs/product-datasheets/cr.pdf"
			(at 0 0 90)
			(layer "F.Fab")
			(hide yes)
			(effects
				(font
					(size 1.27 1.27)
					(thickness 0.15)
				)
			)
		)
		(property "Description" "SMD Chip Resistor, 220 ohm, ± 1%, 62.5 mW, 0402 [1005 Metric], Thick Film, General Purpose"
			(at 0 0 90)
			(layer "F.Fab")
			(hide yes)
			(effects
				(font
					(size 1.27 1.27)
					(thickness 0.15)
				)
			)
		)
		(property "MPN" "CR0402-FX-2200GLF"
			(at 0 0 90)
			(unlocked yes)
			(layer "F.Fab")
			(hide yes)
			(effects
				(font
					(size 1 1)
					(thickness 0.15)
				)
			)
		)
		(property "Manufacturer" "Bourns"
			(at 0 0 90)
			(unlocked yes)
			(layer "F.Fab")
			(hide yes)
			(effects
				(font
					(size 1 1)
					(thickness 0.15)
				)
			)
		)
		(property "License" "Apache-2.0"
			(at 0 0 90)
			(unlocked yes)
			(layer "F.Fab")
			(hide yes)
			(effects
				(font
					(size 1 1)
					(thickness 0.15)
				)
			)
		)
		(property "Author" "Antmicro"
			(at 0 0 90)
			(unlocked yes)
			(layer "F.Fab")
			(hide yes)
			(effects
				(font
					(size 1 1)
					(thickness 0.15)
				)
			)
		)
		(property "Val" "220R"
			(at 0 0 90)
			(unlocked yes)
			(layer "F.Fab")
			(hide yes)
			(effects
				(font
					(size 1 1)
					(thickness 0.15)
				)
			)
		)
		(property "Tolerance" "1%"
			(at 0 0 90)
			(unlocked yes)
			(layer "F.Fab")
			(hide yes)
			(effects
				(font
					(size 1 1)
					(thickness 0.15)
				)
			)
		)
		(sheetname "/DC-DC Converters/")
		(sheetfile "dc-dc_converters.kicad_sch")
		(attr smd)
		(fp_rect
			(start -0.925 -0.47)
			(end 0.925 0.47)
			(stroke
				(width 0.05)
				(type default)
			)
			(fill no)
			(layer "F.CrtYd")
		)
		(fp_rect
			(start -0.5 -0.25)
			(end 0.5 0.25)
			(stroke
				(width 0.15)
				(type solid)
			)
			(fill no)
			(layer "F.Fab")
		)
		(pad "1" smd roundrect
			(at -0.48 0 90)
			(size 0.59 0.64)
			(layers "F.Cu" "F.Mask" "F.Paste")
			(roundrect_rratio 0.25)
			(net 69 "Net-(D9-A)")
			(pintype "passive")
		)
		(pad "2" smd roundrect
			(at 0.48 0 90)
			(size 0.59 0.64)
			(layers "F.Cu" "F.Mask" "F.Paste")
			(roundrect_rratio 0.25)
			(net 1 "+3V3")
			(pintype "passive")
		)
	)
	(footprint "antmicro-footprints:R_0402_1005Metric"
		(layer "F.Cu")
		(at 100 80.577)
		(descr "Resistor SMD 0402")
		(tags "resistor SMD 0402")
		(property "Reference" "R6"
			(at 1.092 0.449 0)
			(layer "F.SilkS")
			(effects
				(font
					(size 0.7 0.7)
					(thickness 0.15)
				)
				(justify left bottom)
			)
		)
		(property "Value" "R_0R_0402"
			(at -1.011843 1.772047 0)
			(layer "F.Fab")
			(effects
				(font
					(size 0.7 0.7)
					(thickness 0.15)
				)
				(justify left bottom)
			)
		)
		(property "Datasheet" "https://industrial.panasonic.com/cdbs/www-data/pdf/RDA0000/AOA0000C301.pdf"
			(at 0 0 0)
			(layer "F.Fab")
			(hide yes)
			(effects
				(font
					(size 1.27 1.27)
					(thickness 0.15)
				)
			)
		)
		(property "Description" "SMD Chip Resistor, Jumper, 0 ohm, 100 mW, 0402 [1005 Metric], Thick Film, General Purpose"
			(at 0 0 0)
			(layer "F.Fab")
			(hide yes)
			(effects
				(font
					(size 1.27 1.27)
					(thickness 0.15)
				)
			)
		)
		(property "Manufacturer" "Panasonic"
			(at 0 0 0)
			(unlocked yes)
			(layer "F.Fab")
			(hide yes)
			(effects
				(font
					(size 1 1)
					(thickness 0.15)
				)
			)
		)
		(property "MPN" "ERJ2GE0R00X"
			(at 0 0 0)
			(unlocked yes)
			(layer "F.Fab")
			(hide yes)
			(effects
				(font
					(size 1 1)
					(thickness 0.15)
				)
			)
		)
		(property "Val" "0R"
			(at 0 0 0)
			(unlocked yes)
			(layer "F.Fab")
			(hide yes)
			(effects
				(font
					(size 1 1)
					(thickness 0.15)
				)
			)
		)
		(property "License" "Apache-2.0"
			(at 0 0 0)
			(unlocked yes)
			(layer "F.Fab")
			(hide yes)
			(effects
				(font
					(size 1 1)
					(thickness 0.15)
				)
			)
		)
		(property "Author" "Antmicro"
			(at 0 0 0)
			(unlocked yes)
			(layer "F.Fab")
			(hide yes)
			(effects
				(font
					(size 1 1)
					(thickness 0.15)
				)
			)
		)
		(property "Tolerance" ""
			(at 0 0 0)
			(unlocked yes)
			(layer "F.Fab")
			(hide yes)
			(effects
				(font
					(size 1 1)
					(thickness 0.15)
				)
			)
		)
		(property "Current" "1A"
			(at 0 0 0)
			(unlocked yes)
			(layer "F.Fab")
			(hide yes)
			(effects
				(font
					(size 1 1)
					(thickness 0.15)
				)
			)
		)
		(sheetname "/DC-DC Converters/")
		(sheetfile "dc-dc_converters.kicad_sch")
		(attr smd)
		(fp_rect
			(start -0.925 -0.47)
			(end 0.925 0.47)
			(stroke
				(width 0.05)
				(type default)
			)
			(fill no)
			(layer "F.CrtYd")
		)
		(fp_rect
			(start -0.5 -0.25)
			(end 0.5 0.25)
			(stroke
				(width 0.15)
				(type solid)
			)
			(fill no)
			(layer "F.Fab")
		)
		(pad "1" smd roundrect
			(at -0.48 0)
			(size 0.59 0.64)
			(layers "F.Cu" "F.Mask" "F.Paste")
			(roundrect_rratio 0.25)
			(net 10 "/DC-DC Converters/VDD_12V_DCDC")
			(pintype "passive")
		)
		(pad "2" smd roundrect
			(at 0.48 0)
			(size 0.59 0.64)
			(layers "F.Cu" "F.Mask" "F.Paste")
			(roundrect_rratio 0.25)
			(net 44 "/DC-DC Converters/12V_ILIM")
			(pintype "passive")
		)
	)
	(footprint "antmicro-footprints:C_0402_1005Metric"
		(layer "F.Cu")
		(at 95.7 88.4 180)
		(descr "Capacitor SMD 0402")
		(tags "capacitor SMD 0402")
		(property "Reference" "C2"
			(at 1.7 -0.6 180)
			(layer "F.SilkS")
			(effects
				(font
					(size 0.7 0.7)
					(thickness 0.15)
				)
				(justify right bottom)
			)
		)
		(property "Value" "C_4u7_25V_0402"
			(at -1.022927 2.155213 0)
			(layer "F.Fab")
			(effects
				(font
					(size 0.7 0.7)
					(thickness 0.15)
				)
				(justify right bottom)
			)
		)
		(property "Datasheet" "https://www.murata.com/products/productdetail?partno=GRM155C61E475ME15%23"
			(at 0 0 180)
			(layer "F.Fab")
			(hide yes)
			(effects
				(font
					(size 1.27 1.27)
					(thickness 0.15)
				)
			)
		)
		(property "Description" "SMD Multilayer Ceramic Capacitor"
			(at 0 0 180)
			(layer "F.Fab")
			(hide yes)
			(effects
				(font
					(size 1.27 1.27)
					(thickness 0.15)
				)
			)
		)
		(property "MPN" "GRM155C61E475ME15J"
			(at 0 0 180)
			(unlocked yes)
			(layer "F.Fab")
			(hide yes)
			(effects
				(font
					(size 1 1)
					(thickness 0.15)
				)
			)
		)
		(property "Manufacturer" "Murata"
			(at 0 0 180)
			(unlocked yes)
			(layer "F.Fab")
			(hide yes)
			(effects
				(font
					(size 1 1)
					(thickness 0.15)
				)
			)
		)
		(property "License" "Apache-2.0"
			(at 0 0 180)
			(unlocked yes)
			(layer "F.Fab")
			(hide yes)
			(effects
				(font
					(size 1 1)
					(thickness 0.15)
				)
			)
		)
		(property "Author" "Antmicro"
			(at 0 0 180)
			(unlocked yes)
			(layer "F.Fab")
			(hide yes)
			(effects
				(font
					(size 1 1)
					(thickness 0.15)
				)
			)
		)
		(property "Val" "4u7"
			(at 0 0 180)
			(unlocked yes)
			(layer "F.Fab")
			(hide yes)
			(effects
				(font
					(size 1 1)
					(thickness 0.15)
				)
			)
		)
		(property "Voltage" "25V"
			(at 0 0 180)
			(unlocked yes)
			(layer "F.Fab")
			(hide yes)
			(effects
				(font
					(size 1 1)
					(thickness 0.15)
				)
			)
		)
		(property "Dielectric" "X5S"
			(at 0 0 180)
			(unlocked yes)
			(layer "F.Fab")
			(hide yes)
			(effects
				(font
					(size 1 1)
					(thickness 0.15)
				)
			)
		)
		(sheetname "/DC-DC Converters/")
		(sheetfile "dc-dc_converters.kicad_sch")
		(attr smd)
		(fp_rect
			(start -0.925 -0.47)
			(end 0.925 0.47)
			(stroke
				(width 0.05)
				(type default)
			)
			(fill no)
			(layer "F.CrtYd")
		)
		(fp_line
			(start 0.504 0.248)
			(end -0.494 0.248)
			(stroke
				(width 0.15)
				(type solid)
			)
			(layer "F.Fab")
		)
		(fp_line
			(start 0.504 -0.25)
			(end 0.504 0.248)
			(stroke
				(width 0.15)
				(type solid)
			)
			(layer "F.Fab")
		)
		(fp_line
			(start -0.494 0.248)
			(end -0.494 -0.25)
			(stroke
				(width 0.15)
				(type solid)
			)
			(layer "F.Fab")
		)
		(fp_line
			(start -0.494 -0.25)
			(end 0.504 -0.25)
			(stroke
				(width 0.15)
				(type solid)
			)
			(layer "F.Fab")
		)
		(pad "1" smd roundrect
			(at -0.48 0 180)
			(size 0.59 0.64)
			(layers "F.Cu" "F.Mask" "F.Paste")
			(roundrect_rratio 0.25)
			(net 2 "GND")
			(pintype "passive")
		)
		(pad "2" smd roundrect
			(at 0.48 0 180)
			(size 0.59 0.64)
			(layers "F.Cu" "F.Mask" "F.Paste")
			(roundrect_rratio 0.25)
			(net 11 "/DC-DC Converters/VDRV_12V_DCDC")
			(pintype "passive")
		)
	)
	(footprint "antmicro-footprints:TP_SMD_0.75mm"
		(layer "F.Cu")
		(at 91.151 78.45)
		(property "Reference" "TP3"
			(at -15.9512 -5.0292 0)
			(layer "F.SilkS")
			(hide yes)
			(effects
				(font
					(size 0.7 0.7)
					(thickness 0.15)
				)
				(justify left bottom)
			)
		)
		(property "Value" "TP_0.75mm_SMD"
			(at 0 1.2 0)
			(layer "F.Fab")
			(effects
				(font
					(size 0.7 0.7)
					(thickness 0.15)
				)
				(justify left bottom)
			)
		)
		(property "Description" "SMT test point"
			(at 0 0 0)
			(layer "F.Fab")
			(hide yes)
			(effects
				(font
					(size 1.27 1.27)
					(thickness 0.15)
				)
			)
		)
		(property "MPN" ""
			(at 0 0 0)
			(unlocked yes)
			(layer "F.Fab")
			(hide yes)
			(effects
				(font
					(size 1 1)
					(thickness 0.15)
				)
			)
		)
		(property "Manufacturer" ""
			(at 0 0 0)
			(unlocked yes)
			(layer "F.Fab")
			(hide yes)
			(effects
				(font
					(size 1 1)
					(thickness 0.15)
				)
			)
		)
		(property "Author" "Antmicro"
			(at 0 0 0)
			(unlocked yes)
			(layer "F.Fab")
			(hide yes)
			(effects
				(font
					(size 1 1)
					(thickness 0.15)
				)
			)
		)
		(property "License" "Apache-2.0"
			(at 0 0 0)
			(unlocked yes)
			(layer "F.Fab")
			(hide yes)
			(effects
				(font
					(size 1 1)
					(thickness 0.15)
				)
			)
		)
		(sheetname "/USB PD/")
		(sheetfile "usb_pd.kicad_sch")
		(attr exclude_from_bom)
		(fp_circle
			(center 0 0)
			(end 0.475 0)
			(stroke
				(width 0.05)
				(type default)
			)
			(fill no)
			(layer "F.CrtYd")
		)
		(pad "1" smd circle
			(at 0 0)
			(size 0.75 0.75)
			(layers "F.Cu" "F.Mask")
			(net 6 "VBUS")
			(pinfunction "1")
			(pintype "passive")
		)
	)
	(footprint "antmicro-footprints:FB_1206_3216Metric"
		(layer "F.Cu")
		(at 83 83.05 -90)
		(property "Reference" "FB2"
			(at 3.2 1.044 0)
			(layer "F.SilkS")
			(effects
				(font
					(size 0.7 0.7)
					(thickness 0.15)
				)
				(justify left bottom)
			)
		)
		(property "Value" "FB_10Z_10A_WE-MPSB_1206"
			(at 0 2 90)
			(layer "F.Fab")
			(effects
				(font
					(size 0.7 0.7)
					(thickness 0.15)
				)
				(justify right bottom)
			)
		)
		(property "Datasheet" "https://www.we-online.com/catalog/datasheet/74279221100.pdf"
			(at 0 0 270)
			(layer "F.Fab")
			(hide yes)
			(effects
				(font
					(size 1.27 1.27)
					(thickness 0.15)
				)
			)
		)
		(property "Description" "Ferrite Bead, 1206 [3216 Metric], 10 ohm, 10.5 A, WE-MPSB, 0.003 ohm, ± 25%, High Current"
			(at 0 0 270)
			(layer "F.Fab")
			(hide yes)
			(effects
				(font
					(size 1.27 1.27)
					(thickness 0.15)
				)
			)
		)
		(property "Val" "10Z/10A"
			(at 0 0 270)
			(unlocked yes)
			(layer "F.Fab")
			(hide yes)
			(effects
				(font
					(size 1 1)
					(thickness 0.15)
				)
			)
		)
		(property "MPN" "74279221100"
			(at 0 0 270)
			(unlocked yes)
			(layer "F.Fab")
			(hide yes)
			(effects
				(font
					(size 1 1)
					(thickness 0.15)
				)
			)
		)
		(property "Manufacturer" "Würth Elektronik"
			(at 0 0 270)
			(unlocked yes)
			(layer "F.Fab")
			(hide yes)
			(effects
				(font
					(size 1 1)
					(thickness 0.15)
				)
			)
		)
		(property "Current" ""
			(at 0 0 270)
			(unlocked yes)
			(layer "F.Fab")
			(hide yes)
			(effects
				(font
					(size 1 1)
					(thickness 0.15)
				)
			)
		)
		(property "Author" "Antmicro"
			(at 0 0 270)
			(unlocked yes)
			(layer "F.Fab")
			(hide yes)
			(effects
				(font
					(size 1 1)
					(thickness 0.15)
				)
			)
		)
		(property "License" "Apache-2.0"
			(at 0 0 270)
			(unlocked yes)
			(layer "F.Fab")
			(hide yes)
			(effects
				(font
					(size 1 1)
					(thickness 0.15)
				)
			)
		)
		(sheetname "/DC-DC Converters/")
		(sheetfile "dc-dc_converters.kicad_sch")
		(attr smd exclude_from_pos_files exclude_from_bom dnp)
		(fp_line
			(start 0.8 0.901)
			(end -0.8 0.901)
			(stroke
				(width 0.15)
				(type solid)
			)
			(layer "F.SilkS")
		)
		(fp_line
			(start 0.8 -0.899)
			(end -0.8 -0.899)
			(stroke
				(width 0.15)
				(type solid)
			)
			(layer "F.SilkS")
		)
		(fp_rect
			(start -2.325 -1.15)
			(end 2.325 1.15)
			(stroke
				(width 0.05)
				(type default)
			)
			(fill no)
			(layer "F.CrtYd")
		)
		(fp_line
			(start -1.677 0.792)
			(end -1.677 -0.861)
			(stroke
				(width 0.15)
				(type solid)
			)
			(layer "F.Fab")
		)
		(fp_line
			(start 1.624 0.792)
			(end -1.677 0.792)
			(stroke
				(width 0.15)
				(type solid)
			)
			(layer "F.Fab")
		)
		(fp_line
			(start -1.677 -0.861)
			(end 1.624 -0.861)
			(stroke
				(width 0.15)
				(type solid)
			)
			(layer "F.Fab")
		)
		(fp_line
			(start 1.624 -0.861)
			(end 1.624 0.792)
			(stroke
				(width 0.15)
				(type solid)
			)
			(layer "F.Fab")
		)
		(pad "1" smd roundrect
			(at -1.5 0.001 270)
			(size 1.15 1.8)
			(layers "F.Cu" "F.Mask" "F.Paste")
			(roundrect_rratio 0.25)
			(net 3 "VCC")
			(pintype "passive")
		)
		(pad "2" smd roundrect
			(at 1.5 0.001 270)
			(size 1.15 1.8)
			(layers "F.Cu" "F.Mask" "F.Paste")
			(roundrect_rratio 0.25)
			(net 5 "+12V")
			(pintype "passive")
		)
	)
	(footprint "antmicro-footprints:R_0402_1005Metric"
		(layer "F.Cu")
		(at 93.799 80.3 -90)
		(descr "Resistor SMD 0402")
		(tags "resistor SMD 0402")
		(property "Reference" "R14"
			(at -0.1 -9.027 180)
			(layer "B.SilkS")
			(effects
				(font
					(size 0.7 0.7)
					(thickness 0.15)
				)
				(justify left bottom mirror)
			)
		)
		(property "Value" "R_3R3_0402"
			(at -1.011843 1.772047 90)
			(layer "F.Fab")
			(effects
				(font
					(size 0.7 0.7)
					(thickness 0.15)
				)
				(justify right bottom)
			)
		)
		(property "Datasheet" "https://www.bourns.com/docs/product-datasheets/cr.pdf"
			(at 0 0 270)
			(layer "F.Fab")
			(hide yes)
			(effects
				(font
					(size 1.27 1.27)
					(thickness 0.15)
				)
			)
		)
		(property "Description" "SMD Chip Resistor, 3.3 ohm, ± 1%, 62.5 mW, 0402 [1005 Metric], Thick Film, General Purpose"
			(at 0 0 270)
			(layer "F.Fab")
			(hide yes)
			(effects
				(font
					(size 1.27 1.27)
					(thickness 0.15)
				)
			)
		)
		(property "Manufacturer" "Bourns"
			(at 0 0 270)
			(unlocked yes)
			(layer "F.Fab")
			(hide yes)
			(effects
				(font
					(size 1 1)
					(thickness 0.15)
				)
			)
		)
		(property "MPN" "CR0402-FX-3R30GLF"
			(at 0 0 270)
			(unlocked yes)
			(layer "F.Fab")
			(hide yes)
			(effects
				(font
					(size 1 1)
					(thickness 0.15)
				)
			)
		)
		(property "Val" "3R3"
			(at 0 0 270)
			(unlocked yes)
			(layer "F.Fab")
			(hide yes)
			(effects
				(font
					(size 1 1)
					(thickness 0.15)
				)
			)
		)
		(property "License" "Apache-2.0"
			(at 0 0 270)
			(unlocked yes)
			(layer "F.Fab")
			(hide yes)
			(effects
				(font
					(size 1 1)
					(thickness 0.15)
				)
			)
		)
		(property "Author" "Antmicro"
			(at 0 0 270)
			(unlocked yes)
			(layer "F.Fab")
			(hide yes)
			(effects
				(font
					(size 1 1)
					(thickness 0.15)
				)
			)
		)
		(property "Tolerance" "1%"
			(at 0 0 270)
			(unlocked yes)
			(layer "F.Fab")
			(hide yes)
			(effects
				(font
					(size 1 1)
					(thickness 0.15)
				)
			)
		)
		(sheetname "/DC-DC Converters/")
		(sheetfile "dc-dc_converters.kicad_sch")
		(attr smd)
		(fp_rect
			(start -0.925 -0.47)
			(end 0.925 0.47)
			(stroke
				(width 0.05)
				(type default)
			)
			(fill no)
			(layer "F.CrtYd")
		)
		(fp_rect
			(start -0.5 -0.25)
			(end 0.5 0.25)
			(stroke
				(width 0.15)
				(type solid)
			)
			(fill no)
			(layer "F.Fab")
		)
		(pad "1" smd roundrect
			(at -0.48 0 270)
			(size 0.59 0.64)
			(layers "F.Cu" "F.Mask" "F.Paste")
			(roundrect_rratio 0.25)
			(net 16 "Net-(C10-Pad1)")
			(pintype "passive")
		)
		(pad "2" smd roundrect
			(at 0.48 0 270)
			(size 0.59 0.64)
			(layers "F.Cu" "F.Mask" "F.Paste")
			(roundrect_rratio 0.25)
			(net 49 "Net-(R14-Pad2)")
			(pintype "passive")
		)
	)
	(footprint "antmicro-footprints:R_0402_1005Metric"
		(layer "F.Cu")
		(at 82.35 69.75 90)
		(descr "Resistor SMD 0402")
		(tags "resistor SMD 0402")
		(property "Reference" "R32"
			(at 1.17 0.454 90)
			(layer "F.SilkS")
			(effects
				(font
					(size 0.7 0.7)
					(thickness 0.15)
				)
				(justify left bottom)
			)
		)
		(property "Value" "R_4k7_0402"
			(at -1.011843 1.772047 90)
			(layer "F.Fab")
			(effects
				(font
					(size 0.7 0.7)
					(thickness 0.15)
				)
				(justify left bottom)
			)
		)
		(property "Datasheet" "https://www.bourns.com/docs/product-datasheets/cr.pdf"
			(at 0 0 90)
			(layer "F.Fab")
			(hide yes)
			(effects
				(font
					(size 1.27 1.27)
					(thickness 0.15)
				)
			)
		)
		(property "Description" "SMD Chip Resistor, 4.7 kohm, ± 1%, 62.5 mW, 0402 [1005 Metric], Thick Film, General Purpose"
			(at 0 0 90)
			(layer "F.Fab")
			(hide yes)
			(effects
				(font
					(size 1.27 1.27)
					(thickness 0.15)
				)
			)
		)
		(property "MPN" "CR0402-FX-4701GLF"
			(at 0 0 90)
			(unlocked yes)
			(layer "F.Fab")
			(hide yes)
			(effects
				(font
					(size 1 1)
					(thickness 0.15)
				)
			)
		)
		(property "Manufacturer" "Bourns"
			(at 0 0 90)
			(unlocked yes)
			(layer "F.Fab")
			(hide yes)
			(effects
				(font
					(size 1 1)
					(thickness 0.15)
				)
			)
		)
		(property "License" "Apache-2.0"
			(at 0 0 90)
			(unlocked yes)
			(layer "F.Fab")
			(hide yes)
			(effects
				(font
					(size 1 1)
					(thickness 0.15)
				)
			)
		)
		(property "Author" "Antmicro"
			(at 0 0 90)
			(unlocked yes)
			(layer "F.Fab")
			(hide yes)
			(effects
				(font
					(size 1 1)
					(thickness 0.15)
				)
			)
		)
		(property "Val" "4k7"
			(at 0 0 90)
			(unlocked yes)
			(layer "F.Fab")
			(hide yes)
			(effects
				(font
					(size 1 1)
					(thickness 0.15)
				)
			)
		)
		(property "Tolerance" "1%"
			(at 0 0 90)
			(unlocked yes)
			(layer "F.Fab")
			(hide yes)
			(effects
				(font
					(size 1 1)
					(thickness 0.15)
				)
			)
		)
		(sheetname "/USB PD/")
		(sheetfile "usb_pd.kicad_sch")
		(attr smd exclude_from_pos_files exclude_from_bom dnp)
		(fp_rect
			(start -0.925 -0.47)
			(end 0.925 0.47)
			(stroke
				(width 0.05)
				(type default)
			)
			(fill no)
			(layer "F.CrtYd")
		)
		(fp_rect
			(start -0.5 -0.25)
			(end 0.5 0.25)
			(stroke
				(width 0.15)
				(type solid)
			)
			(fill no)
			(layer "F.Fab")
		)
		(pad "1" smd roundrect
			(at -0.48 0 90)
			(size 0.59 0.64)
			(layers "F.Cu" "F.Mask" "F.Paste")
			(roundrect_rratio 0.25)
			(net 37 "/USB PD/SDA")
			(pintype "passive")
		)
		(pad "2" smd roundrect
			(at 0.48 0 90)
			(size 0.59 0.64)
			(layers "F.Cu" "F.Mask" "F.Paste")
			(roundrect_rratio 0.25)
			(net 1 "+3V3")
			(pintype "passive")
		)
	)
	(footprint "antmicro-footprints:C_Pol_Vishay-T59-EE"
		(layer "F.Cu")
		(at 90.676 95.55 -90)
		(property "Reference" "C43"
			(at -4.95 3.676 0)
			(unlocked yes)
			(layer "F.SilkS")
			(effects
				(font
					(size 0.7 0.7)
					(thickness 0.15)
				)
				(justify left bottom)
			)
		)
		(property "Value" "C_Pol_150u_30V_Vishay-T59-EE"
			(at -5.08 5.08 270)
			(unlocked yes)
			(layer "F.Fab")
			(effects
				(font
					(size 0.7 0.7)
					(thickness 0.15)
				)
				(justify left bottom)
			)
		)
		(property "Datasheet" "https://www.vishay.com/docs/40191/t59.pdf"
			(at 0 0 270)
			(layer "F.Fab")
			(hide yes)
			(effects
				(font
					(size 1.27 1.27)
					(thickness 0.15)
				)
			)
		)
		(property "Description" "Tantalum Capacitors - Polymer 150uF 30volts 20% 75mohms maxESR"
			(at 0 0 270)
			(layer "F.Fab")
			(hide yes)
			(effects
				(font
					(size 1.27 1.27)
					(thickness 0.15)
				)
			)
		)
		(property "MPN" "T59EE157M030C0075"
			(at 0 0 270)
			(unlocked yes)
			(layer "F.Fab")
			(hide yes)
			(effects
				(font
					(size 1 1)
					(thickness 0.15)
				)
			)
		)
		(property "Manufacturer" "Vishay"
			(at 0 0 270)
			(unlocked yes)
			(layer "F.Fab")
			(hide yes)
			(effects
				(font
					(size 1 1)
					(thickness 0.15)
				)
			)
		)
		(property "Voltage" "30V"
			(at 0 0 270)
			(unlocked yes)
			(layer "F.Fab")
			(hide yes)
			(effects
				(font
					(size 1 1)
					(thickness 0.15)
				)
			)
		)
		(property "Val" "150u"
			(at 0 0 270)
			(unlocked yes)
			(layer "F.Fab")
			(hide yes)
			(effects
				(font
					(size 1 1)
					(thickness 0.15)
				)
			)
		)
		(property "Author" "Antmicro"
			(at 0 0 270)
			(unlocked yes)
			(layer "F.Fab")
			(hide yes)
			(effects
				(font
					(size 1 1)
					(thickness 0.15)
				)
			)
		)
		(property "License" "Apache-2.0"
			(at 0 0 270)
			(unlocked yes)
			(layer "F.Fab")
			(hide yes)
			(effects
				(font
					(size 1 1)
					(thickness 0.15)
				)
			)
		)
		(property "Dielectric" "template_dielectric"
			(at 0 0 270)
			(unlocked yes)
			(layer "F.Fab")
			(hide yes)
			(effects
				(font
					(size 1 1)
					(thickness 0.15)
				)
			)
		)
		(sheetname "/DC-DC Converters/")
		(sheetfile "dc-dc_converters.kicad_sch")
		(attr smd)
		(fp_line
			(start -2 2.25)
			(end 2 2.25)
			(stroke
				(width 0.15)
				(type solid)
			)
			(layer "F.SilkS")
		)
		(fp_line
			(start -2 -2.25)
			(end 2 -2.25)
			(stroke
				(width 0.15)
				(type solid)
			)
			(layer "F.SilkS")
		)
		(fp_line
			(start -3.5 -2.8)
			(end -3.5 -3.2)
			(stroke
				(width 0.15)
				(type solid)
			)
			(layer "F.SilkS")
		)
		(fp_line
			(start -3.7 -3)
			(end -3.3 -3)
			(stroke
				(width 0.15)
				(type solid)
			)
			(layer "F.SilkS")
		)
		(fp_rect
			(start -4.9 -2.9)
			(end 4.9 2.9)
			(stroke
				(width 0.05)
				(type solid)
			)
			(fill no)
			(layer "F.CrtYd")
		)
		(fp_rect
			(start -3.75 -2.25)
			(end 3.75 2.25)
			(stroke
				(width 0.15)
				(type solid)
			)
			(fill no)
			(layer "F.Fab")
		)
		(pad "1" smd trapezoid
			(at -3.4 0 270)
			(size 2.5 5.3)
			(layers "F.Cu" "F.Mask" "F.Paste")
			(net 12 "Net-(U2-V_{CIN})")
			(pintype "passive")
		)
		(pad "2" smd trapezoid
			(at 3.4 0 270)
			(size 2.5 5.3)
			(layers "F.Cu" "F.Mask" "F.Paste")
			(net 2 "GND")
			(pintype "passive")
		)
	)
	(footprint "antmicro-footprints:FB_1206_3216Metric"
		(layer "F.Cu")
		(at 85.35 83.05 -90)
		(property "Reference" "FB1"
			(at 3.16 -1.046 180)
			(layer "F.SilkS")
			(effects
				(font
					(size 0.7 0.7)
					(thickness 0.15)
				)
				(justify right bottom)
			)
		)
		(property "Value" "FB_10Z_10A_WE-MPSB_1206"
			(at 0 2 90)
			(layer "F.Fab")
			(effects
				(font
					(size 0.7 0.7)
					(thickness 0.15)
				)
				(justify right bottom)
			)
		)
		(property "Datasheet" "https://www.we-online.com/catalog/datasheet/74279221100.pdf"
			(at 0 0 270)
			(layer "F.Fab")
			(hide yes)
			(effects
				(font
					(size 1.27 1.27)
					(thickness 0.15)
				)
			)
		)
		(property "Description" "Ferrite Bead, 1206 [3216 Metric], 10 ohm, 10.5 A, WE-MPSB, 0.003 ohm, ± 25%, High Current"
			(at 0 0 270)
			(layer "F.Fab")
			(hide yes)
			(effects
				(font
					(size 1.27 1.27)
					(thickness 0.15)
				)
			)
		)
		(property "MPN" "74279221100"
			(at 0 0 270)
			(unlocked yes)
			(layer "F.Fab")
			(hide yes)
			(effects
				(font
					(size 1 1)
					(thickness 0.15)
				)
			)
		)
		(property "Manufacturer" "Würth Elektronik"
			(at 0 0 270)
			(unlocked yes)
			(layer "F.Fab")
			(hide yes)
			(effects
				(font
					(size 1 1)
					(thickness 0.15)
				)
			)
		)
		(property "Author" "Antmicro"
			(at 0 0 270)
			(unlocked yes)
			(layer "F.Fab")
			(hide yes)
			(effects
				(font
					(size 1 1)
					(thickness 0.15)
				)
			)
		)
		(property "License" "Apache-2.0"
			(at 0 0 270)
			(unlocked yes)
			(layer "F.Fab")
			(hide yes)
			(effects
				(font
					(size 1 1)
					(thickness 0.15)
				)
			)
		)
		(property "Val" "10Z/10A"
			(at 0 0 270)
			(unlocked yes)
			(layer "F.Fab")
			(hide yes)
			(effects
				(font
					(size 1 1)
					(thickness 0.15)
				)
			)
		)
		(property "Current" ""
			(at 0 0 270)
			(unlocked yes)
			(layer "F.Fab")
			(hide yes)
			(effects
				(font
					(size 1 1)
					(thickness 0.15)
				)
			)
		)
		(sheetname "/DC-DC Converters/")
		(sheetfile "dc-dc_converters.kicad_sch")
		(attr smd)
		(fp_line
			(start 0.8 0.901)
			(end -0.8 0.901)
			(stroke
				(width 0.15)
				(type solid)
			)
			(layer "F.SilkS")
		)
		(fp_line
			(start 0.8 -0.899)
			(end -0.8 -0.899)
			(stroke
				(width 0.15)
				(type solid)
			)
			(layer "F.SilkS")
		)
		(fp_rect
			(start -2.325 -1.15)
			(end 2.325 1.15)
			(stroke
				(width 0.05)
				(type default)
			)
			(fill no)
			(layer "F.CrtYd")
		)
		(fp_line
			(start -1.677 0.792)
			(end -1.677 -0.861)
			(stroke
				(width 0.15)
				(type solid)
			)
			(layer "F.Fab")
		)
		(fp_line
			(start 1.624 0.792)
			(end -1.677 0.792)
			(stroke
				(width 0.15)
				(type solid)
			)
			(layer "F.Fab")
		)
		(fp_line
			(start -1.677 -0.861)
			(end 1.624 -0.861)
			(stroke
				(width 0.15)
				(type solid)
			)
			(layer "F.Fab")
		)
		(fp_line
			(start 1.624 -0.861)
			(end 1.624 0.792)
			(stroke
				(width 0.15)
				(type solid)
			)
			(layer "F.Fab")
		)
		(pad "1" smd roundrect
			(at -1.5 0.001 270)
			(size 1.15 1.8)
			(layers "F.Cu" "F.Mask" "F.Paste")
			(roundrect_rratio 0.25)
			(net 3 "VCC")
			(pintype "passive")
		)
		(pad "2" smd roundrect
			(at 1.5 0.001 270)
			(size 1.15 1.8)
			(layers "F.Cu" "F.Mask" "F.Paste")
			(roundrect_rratio 0.25)
			(net 12 "Net-(U2-V_{CIN})")
			(pintype "passive")
		)
	)
	(footprint "antmicro-footprints:LED_0603_1608Metric_G"
		(layer "F.Cu")
		(at 98.35 74.55 90)
		(descr "LED SMD 0603 Green")
		(tags "LED SMD 0603 Green")
		(property "Reference" "D6"
			(at -6.8 0.126 0)
			(layer "B.SilkS")
			(effects
				(font
					(size 0.7 0.7)
					(thickness 0.15)
				)
				(justify right bottom mirror)
			)
		)
		(property "Value" "LED_G_0603_LG_L29K-G2J1-24-Z"
			(at -0.001 1.599 90)
			(layer "F.Fab")
			(effects
				(font
					(size 0.7 0.7)
					(thickness 0.15)
				)
				(justify left bottom)
			)
		)
		(property "Datasheet" "https://look.ams-osram.com/m/19ee86b3ae0ee95b/original/LG-L29K.pdf"
			(at 0 0 90)
			(layer "F.Fab")
			(hide yes)
			(effects
				(font
					(size 1.27 1.27)
					(thickness 0.15)
				)
			)
		)
		(property "Description" "LED, Green, SMD, 0603, 20 mA, 1.7 V, 570 nm"
			(at 0 0 90)
			(layer "F.Fab")
			(hide yes)
			(effects
				(font
					(size 1.27 1.27)
					(thickness 0.15)
				)
			)
		)
		(property "MPN" "LG L29K-G2J1-24-Z"
			(at 0 0 90)
			(unlocked yes)
			(layer "F.Fab")
			(hide yes)
			(effects
				(font
					(size 1 1)
					(thickness 0.15)
				)
			)
		)
		(property "Manufacturer" "OSRAM"
			(at 0 0 90)
			(unlocked yes)
			(layer "F.Fab")
			(hide yes)
			(effects
				(font
					(size 1 1)
					(thickness 0.15)
				)
			)
		)
		(property "Color" "Green"
			(at 0 0 90)
			(unlocked yes)
			(layer "F.Fab")
			(hide yes)
			(effects
				(font
					(size 1 1)
					(thickness 0.15)
				)
			)
		)
		(property "Author" "Antmicro"
			(at 0 0 90)
			(unlocked yes)
			(layer "F.Fab")
			(hide yes)
			(effects
				(font
					(size 1 1)
					(thickness 0.15)
				)
			)
		)
		(property "License" "Apache-2.0"
			(at 0 0 90)
			(unlocked yes)
			(layer "F.Fab")
			(hide yes)
			(effects
				(font
					(size 1 1)
					(thickness 0.15)
				)
			)
		)
		(sheetname "/USB PD/")
		(sheetfile "usb_pd.kicad_sch")
		(attr smd)
		(fp_line
			(start 0.22 -0.35)
			(end -0.22 -0.35)
			(stroke
				(width 0.15)
				(type solid)
			)
			(layer "F.SilkS")
		)
		(fp_line
			(start -1.18 -0.319)
			(end -1.18 0.321)
			(stroke
				(width 0.15)
				(type solid)
			)
			(layer "F.SilkS")
		)
		(fp_line
			(start 0.105328 0.001008)
			(end 0.24 0.001)
			(stroke
				(width 0.1)
				(type solid)
			)
			(layer "F.SilkS")
		)
		(fp_line
			(start -0.094672 0.001008)
			(end 0.105328 -0.198992)
			(stroke
				(width 0.1)
				(type solid)
			)
			(layer "F.SilkS")
		)
		(fp_line
			(start -0.094672 0.001008)
			(end -0.24 0.001008)
			(stroke
				(width 0.1)
				(type solid)
			)
			(layer "F.SilkS")
		)
		(fp_line
			(start 0.105328 0.201008)
			(end 0.105328 -0.198992)
			(stroke
				(width 0.1)
				(type solid)
			)
			(layer "F.SilkS")
		)
		(fp_line
			(start 0.105328 0.201008)
			(end -0.094672 0.001008)
			(stroke
				(width 0.1)
				(type solid)
			)
			(layer "F.SilkS")
		)
		(fp_line
			(start -0.094672 0.201008)
			(end -0.094672 -0.198992)
			(stroke
				(width 0.1)
				(type solid)
			)
			(layer "F.SilkS")
		)
		(fp_line
			(start 0.22 0.35)
			(end -0.22 0.35)
			(stroke
				(width 0.15)
				(type solid)
			)
			(layer "F.SilkS")
		)
		(fp_rect
			(start 1.25 0.65)
			(end -1.25 -0.65)
			(stroke
				(width 0.05)
				(type solid)
			)
			(fill no)
			(layer "F.CrtYd")
		)
		(fp_line
			(start 0.201 -0.202)
			(end -0.101 0)
			(stroke
				(width 0.15)
				(type solid)
			)
			(layer "F.Fab")
		)
		(fp_line
			(start -0.199 -0.202)
			(end -0.199 0.1)
			(stroke
				(width 0.15)
				(type solid)
			)
			(layer "F.Fab")
		)
		(fp_line
			(start 0.599 0)
			(end 0.201 0)
			(stroke
				(width 0.15)
				(type solid)
			)
			(layer "F.Fab")
		)
		(fp_line
			(start 0.201 0)
			(end 0.201 -0.202)
			(stroke
				(width 0.15)
				(type solid)
			)
			(layer "F.Fab")
		)
		(fp_line
			(start -0.101 0)
			(end 0.201 0.2)
			(stroke
				(width 0.15)
				(type solid)
			)
			(layer "F.Fab")
		)
		(fp_line
			(start -0.199 0)
			(end -0.597 0)
			(stroke
				(width 0.15)
				(type solid)
			)
			(layer "F.Fab")
		)
		(fp_line
			(start 0.201 0.2)
			(end 0.201 0)
			(stroke
				(width 0.15)
				(type solid)
			)
			(layer "F.Fab")
		)
		(fp_line
			(start -0.199 0.2)
			(end -0.199 0.1)
			(stroke
				(width 0.15)
				(type solid)
			)
			(layer "F.Fab")
		)
		(fp_rect
			(start 0.848 0.4)
			(end -0.85 -0.402)
			(stroke
				(width 0.15)
				(type solid)
			)
			(fill no)
			(layer "F.Fab")
		)
		(pad "1" smd roundrect
			(at -0.7 0 270)
			(size 0.8 1)
			(layers "F.Cu" "F.Mask" "F.Paste")
			(roundrect_rratio 0.2)
			(net 27 "POWER_OK2")
			(pinfunction "C")
			(pintype "passive")
		)
		(pad "2" smd roundrect
			(at 0.7 0 270)
			(size 0.8 1)
			(layers "F.Cu" "F.Mask" "F.Paste")
			(roundrect_rratio 0.2)
			(net 66 "Net-(D6-A)")
			(pinfunction "A")
			(pintype "passive")
		)
	)
	(footprint "antmicro-footprints:C_0402_1005Metric"
		(layer "F.Cu")
		(at 100.5 88.6)
		(descr "Capacitor SMD 0402")
		(tags "capacitor SMD 0402")
		(property "Reference" "C14"
			(at 2.7 1.8 90)
			(layer "F.SilkS")
			(effects
				(font
					(size 0.7 0.7)
					(thickness 0.15)
				)
				(justify left bottom)
			)
		)
		(property "Value" "C_1n2_50V_0402"
			(at -1.022927 2.155213 0)
			(layer "F.Fab")
			(effects
				(font
					(size 0.7 0.7)
					(thickness 0.15)
				)
				(justify left bottom)
			)
		)
		(property "Datasheet" "https://www.murata.com/products/productdetail?partno=GCM155R71H122KA37%23"
			(at 0 0 0)
			(layer "F.Fab")
			(hide yes)
			(effects
				(font
					(size 1.27 1.27)
					(thickness 0.15)
				)
			)
		)
		(property "Description" "SMD Multilayer Ceramic Capacitor, 1200 pF, 50 V, 0402 [1005 Metric], ± 10%, X7R, GCM"
			(at 0 0 0)
			(layer "F.Fab")
			(hide yes)
			(effects
				(font
					(size 1.27 1.27)
					(thickness 0.15)
				)
			)
		)
		(property "Manufacturer" "Murata"
			(at 0 0 0)
			(unlocked yes)
			(layer "F.Fab")
			(hide yes)
			(effects
				(font
					(size 1 1)
					(thickness 0.15)
				)
			)
		)
		(property "MPN" "GCM155R71H122KA37D"
			(at 0 0 0)
			(unlocked yes)
			(layer "F.Fab")
			(hide yes)
			(effects
				(font
					(size 1 1)
					(thickness 0.15)
				)
			)
		)
		(property "Val" "1n2"
			(at 0 0 0)
			(unlocked yes)
			(layer "F.Fab")
			(hide yes)
			(effects
				(font
					(size 1 1)
					(thickness 0.15)
				)
			)
		)
		(property "License" "Apache-2.0"
			(at 0 0 0)
			(unlocked yes)
			(layer "F.Fab")
			(hide yes)
			(effects
				(font
					(size 1 1)
					(thickness 0.15)
				)
			)
		)
		(property "Author" "Antmicro"
			(at 0 0 0)
			(unlocked yes)
			(layer "F.Fab")
			(hide yes)
			(effects
				(font
					(size 1 1)
					(thickness 0.15)
				)
			)
		)
		(property "Voltage" "50V"
			(at 0 0 0)
			(unlocked yes)
			(layer "F.Fab")
			(hide yes)
			(effects
				(font
					(size 1 1)
					(thickness 0.15)
				)
			)
		)
		(property "Dielectric" ""
			(at 0 0 0)
			(unlocked yes)
			(layer "F.Fab")
			(hide yes)
			(effects
				(font
					(size 1 1)
					(thickness 0.15)
				)
			)
		)
		(sheetname "/DC-DC Converters/")
		(sheetfile "dc-dc_converters.kicad_sch")
		(attr smd exclude_from_pos_files exclude_from_bom dnp)
		(fp_rect
			(start -0.925 -0.47)
			(end 0.925 0.47)
			(stroke
				(width 0.05)
				(type default)
			)
			(fill no)
			(layer "F.CrtYd")
		)
		(fp_line
			(start -0.494 -0.25)
			(end 0.504 -0.25)
			(stroke
				(width 0.15)
				(type solid)
			)
			(layer "F.Fab")
		)
		(fp_line
			(start -0.494 0.248)
			(end -0.494 -0.25)
			(stroke
				(width 0.15)
				(type solid)
			)
			(layer "F.Fab")
		)
		(fp_line
			(start 0.504 -0.25)
			(end 0.504 0.248)
			(stroke
				(width 0.15)
				(type solid)
			)
			(layer "F.Fab")
		)
		(fp_line
			(start 0.504 0.248)
			(end -0.494 0.248)
			(stroke
				(width 0.15)
				(type solid)
			)
			(layer "F.Fab")
		)
		(pad "1" smd roundrect
			(at -0.48 0)
			(size 0.59 0.64)
			(layers "F.Cu" "F.Mask" "F.Paste")
			(roundrect_rratio 0.25)
			(net 19 "/DC-DC Converters/12V_SNS")
			(pintype "passive")
		)
		(pad "2" smd roundrect
			(at 0.48 0)
			(size 0.59 0.64)
			(layers "F.Cu" "F.Mask" "F.Paste")
			(roundrect_rratio 0.25)
			(net 5 "+12V")
			(pintype "passive")
		)
	)
	(footprint "antmicro-footprints:R_0402_1005Metric"
		(layer "F.Cu")
		(at 100 83.577 180)
		(descr "Resistor SMD 0402")
		(tags "resistor SMD 0402")
		(property "Reference" "R18"
			(at -1.092 -0.497 0)
			(layer "F.SilkS")
			(effects
				(font
					(size 0.7 0.7)
					(thickness 0.15)
				)
				(justify left bottom)
			)
		)
		(property "Value" "R_10k_0.1%_0402"
			(at -1.011843 1.772047 0)
			(layer "F.Fab")
			(effects
				(font
					(size 0.7 0.7)
					(thickness 0.15)
				)
				(justify right bottom)
			)
		)
		(property "Datasheet" "https://www.mouser.com/datasheet/2/54/CRT-1649066.pdf"
			(at 0 0 180)
			(layer "F.Fab")
			(hide yes)
			(effects
				(font
					(size 1.27 1.27)
					(thickness 0.15)
				)
			)
		)
		(property "Description" "SMD Chip Resistor, 10 kohm, ± 0.1%, 62.5 mW, 0402 [1005 Metric], Thin Film, Precision Resistors"
			(at 0 0 180)
			(layer "F.Fab")
			(hide yes)
			(effects
				(font
					(size 1.27 1.27)
					(thickness 0.15)
				)
			)
		)
		(property "MPN" "CRT0402-BY-1002GLF "
			(at 0 0 180)
			(unlocked yes)
			(layer "F.Fab")
			(hide yes)
			(effects
				(font
					(size 1 1)
					(thickness 0.15)
				)
			)
		)
		(property "Val" "10k"
			(at 0 0 180)
			(unlocked yes)
			(layer "F.Fab")
			(hide yes)
			(effects
				(font
					(size 1 1)
					(thickness 0.15)
				)
			)
		)
		(property "Manufacturer" "Bourns"
			(at 0 0 180)
			(unlocked yes)
			(layer "F.Fab")
			(hide yes)
			(effects
				(font
					(size 1 1)
					(thickness 0.15)
				)
			)
		)
		(property "Tolerance" "0.1%"
			(at 0 0 180)
			(unlocked yes)
			(layer "F.Fab")
			(hide yes)
			(effects
				(font
					(size 1 1)
					(thickness 0.15)
				)
			)
		)
		(property "License" "Apache-2.0"
			(at 0 0 180)
			(unlocked yes)
			(layer "F.Fab")
			(hide yes)
			(effects
				(font
					(size 1 1)
					(thickness 0.15)
				)
			)
		)
		(property "Author" "Antmicro"
			(at 0 0 180)
			(unlocked yes)
			(layer "F.Fab")
			(hide yes)
			(effects
				(font
					(size 1 1)
					(thickness 0.15)
				)
			)
		)
		(sheetname "/DC-DC Converters/")
		(sheetfile "dc-dc_converters.kicad_sch")
		(attr smd)
		(fp_rect
			(start -0.925 -0.47)
			(end 0.925 0.47)
			(stroke
				(width 0.05)
				(type default)
			)
			(fill no)
			(layer "F.CrtYd")
		)
		(fp_rect
			(start -0.5 -0.25)
			(end 0.5 0.25)
			(stroke
				(width 0.15)
				(type solid)
			)
			(fill no)
			(layer "F.Fab")
		)
		(pad "1" smd roundrect
			(at -0.48 0 180)
			(size 0.59 0.64)
			(layers "F.Cu" "F.Mask" "F.Paste")
			(roundrect_rratio 0.25)
			(net 2 "GND")
			(pintype "passive")
		)
		(pad "2" smd roundrect
			(at 0.48 0 180)
			(size 0.59 0.64)
			(layers "F.Cu" "F.Mask" "F.Paste")
			(roundrect_rratio 0.25)
			(net 51 "Net-(U2-V_{FB})")
			(pintype "passive")
		)
	)
	(footprint "antmicro-footprints:R_0402_1005Metric"
		(layer "F.Cu")
		(at 101.226 72.35 90)
		(descr "Resistor SMD 0402")
		(tags "resistor SMD 0402")
		(property "Reference" "R29"
			(at -6.898 -2.752 0)
			(layer "B.SilkS")
			(effects
				(font
					(size 0.7 0.7)
					(thickness 0.15)
				)
				(justify left bottom mirror)
			)
		)
		(property "Value" "R_470_0402"
			(at -1.011843 1.772047 90)
			(layer "F.Fab")
			(effects
				(font
					(size 0.7 0.7)
					(thickness 0.15)
				)
				(justify left bottom)
			)
		)
		(property "Datasheet" "https://www.bourns.com/docs/product-datasheets/cr.pdf"
			(at 0 0 90)
			(layer "F.Fab")
			(hide yes)
			(effects
				(font
					(size 1.27 1.27)
					(thickness 0.15)
				)
			)
		)
		(property "Description" "SMD Chip Resistor, 470 ohm, ± 1%, 62.5 mW, 0402 [1005 Metric], Thick Film, General Purpose"
			(at 0 0 90)
			(layer "F.Fab")
			(hide yes)
			(effects
				(font
					(size 1.27 1.27)
					(thickness 0.15)
				)
			)
		)
		(property "MPN" "CR0402-FX-4700GLF"
			(at 0 0 90)
			(unlocked yes)
			(layer "F.Fab")
			(hide yes)
			(effects
				(font
					(size 1 1)
					(thickness 0.15)
				)
			)
		)
		(property "Manufacturer" "Bourns"
			(at 0 0 90)
			(unlocked yes)
			(layer "F.Fab")
			(hide yes)
			(effects
				(font
					(size 1 1)
					(thickness 0.15)
				)
			)
		)
		(property "License" "Apache-2.0"
			(at 0 0 90)
			(unlocked yes)
			(layer "F.Fab")
			(hide yes)
			(effects
				(font
					(size 1 1)
					(thickness 0.15)
				)
			)
		)
		(property "Author" "Antmicro"
			(at 0 0 90)
			(unlocked yes)
			(layer "F.Fab")
			(hide yes)
			(effects
				(font
					(size 1 1)
					(thickness 0.15)
				)
			)
		)
		(property "Val" "470R"
			(at 0 0 90)
			(unlocked yes)
			(layer "F.Fab")
			(hide yes)
			(effects
				(font
					(size 1 1)
					(thickness 0.15)
				)
			)
		)
		(property "Tolerance" "1%"
			(at 0 0 90)
			(unlocked yes)
			(layer "F.Fab")
			(hide yes)
			(effects
				(font
					(size 1 1)
					(thickness 0.15)
				)
			)
		)
		(sheetname "/DC-DC Converters/")
		(sheetfile "dc-dc_converters.kicad_sch")
		(attr smd)
		(fp_rect
			(start -0.925 -0.47)
			(end 0.925 0.47)
			(stroke
				(width 0.05)
				(type default)
			)
			(fill no)
			(layer "F.CrtYd")
		)
		(fp_rect
			(start -0.5 -0.25)
			(end 0.5 0.25)
			(stroke
				(width 0.15)
				(type solid)
			)
			(fill no)
			(layer "F.Fab")
		)
		(pad "1" smd roundrect
			(at -0.48 0 90)
			(size 0.59 0.64)
			(layers "F.Cu" "F.Mask" "F.Paste")
			(roundrect_rratio 0.25)
			(net 68 "Net-(D8-A)")
			(pintype "passive")
		)
		(pad "2" smd roundrect
			(at 0.48 0 90)
			(size 0.59 0.64)
			(layers "F.Cu" "F.Mask" "F.Paste")
			(roundrect_rratio 0.25)
			(net 25 "+5V")
			(pintype "passive")
		)
	)
	(footprint "antmicro-footprints:LED_0603_1608Metric_G"
		(layer "F.Cu")
		(at 97 74.55 90)
		(descr "LED SMD 0603 Green")
		(tags "LED SMD 0603 Green")
		(property "Reference" "D3"
			(at -7.8 1.476 0)
			(layer "B.SilkS")
			(effects
				(font
					(size 0.7 0.7)
					(thickness 0.15)
				)
				(justify right bottom mirror)
			)
		)
		(property "Value" "LED_G_0603_LG_L29K-G2J1-24-Z"
			(at -0.001 1.599 90)
			(layer "F.Fab")
			(effects
				(font
					(size 0.7 0.7)
					(thickness 0.15)
				)
				(justify left bottom)
			)
		)
		(property "Datasheet" "https://look.ams-osram.com/m/19ee86b3ae0ee95b/original/LG-L29K.pdf"
			(at 0 0 90)
			(layer "F.Fab")
			(hide yes)
			(effects
				(font
					(size 1.27 1.27)
					(thickness 0.15)
				)
			)
		)
		(property "Description" "LED, Green, SMD, 0603, 20 mA, 1.7 V, 570 nm"
			(at 0 0 90)
			(layer "F.Fab")
			(hide yes)
			(effects
				(font
					(size 1.27 1.27)
					(thickness 0.15)
				)
			)
		)
		(property "MPN" "LG L29K-G2J1-24-Z"
			(at 0 0 90)
			(unlocked yes)
			(layer "F.Fab")
			(hide yes)
			(effects
				(font
					(size 1 1)
					(thickness 0.15)
				)
			)
		)
		(property "Manufacturer" "OSRAM"
			(at 0 0 90)
			(unlocked yes)
			(layer "F.Fab")
			(hide yes)
			(effects
				(font
					(size 1 1)
					(thickness 0.15)
				)
			)
		)
		(property "Color" "Green"
			(at 0 0 90)
			(unlocked yes)
			(layer "F.Fab")
			(hide yes)
			(effects
				(font
					(size 1 1)
					(thickness 0.15)
				)
			)
		)
		(property "Author" "Antmicro"
			(at 0 0 90)
			(unlocked yes)
			(layer "F.Fab")
			(hide yes)
			(effects
				(font
					(size 1 1)
					(thickness 0.15)
				)
			)
		)
		(property "License" "Apache-2.0"
			(at 0 0 90)
			(unlocked yes)
			(layer "F.Fab")
			(hide yes)
			(effects
				(font
					(size 1 1)
					(thickness 0.15)
				)
			)
		)
		(sheetname "/USB PD/")
		(sheetfile "usb_pd.kicad_sch")
		(attr smd)
		(fp_line
			(start 0.22 -0.35)
			(end -0.22 -0.35)
			(stroke
				(width 0.15)
				(type solid)
			)
			(layer "F.SilkS")
		)
		(fp_line
			(start -1.18 -0.319)
			(end -1.18 0.321)
			(stroke
				(width 0.15)
				(type solid)
			)
			(layer "F.SilkS")
		)
		(fp_line
			(start 0.105328 0.001008)
			(end 0.24 0.001)
			(stroke
				(width 0.1)
				(type solid)
			)
			(layer "F.SilkS")
		)
		(fp_line
			(start -0.094672 0.001008)
			(end 0.105328 -0.198992)
			(stroke
				(width 0.1)
				(type solid)
			)
			(layer "F.SilkS")
		)
		(fp_line
			(start -0.094672 0.001008)
			(end -0.24 0.001008)
			(stroke
				(width 0.1)
				(type solid)
			)
			(layer "F.SilkS")
		)
		(fp_line
			(start 0.105328 0.201008)
			(end 0.105328 -0.198992)
			(stroke
				(width 0.1)
				(type solid)
			)
			(layer "F.SilkS")
		)
		(fp_line
			(start 0.105328 0.201008)
			(end -0.094672 0.001008)
			(stroke
				(width 0.1)
				(type solid)
			)
			(layer "F.SilkS")
		)
		(fp_line
			(start -0.094672 0.201008)
			(end -0.094672 -0.198992)
			(stroke
				(width 0.1)
				(type solid)
			)
			(layer "F.SilkS")
		)
		(fp_line
			(start 0.22 0.35)
			(end -0.22 0.35)
			(stroke
				(width 0.15)
				(type solid)
			)
			(layer "F.SilkS")
		)
		(fp_rect
			(start 1.25 0.65)
			(end -1.25 -0.65)
			(stroke
				(width 0.05)
				(type solid)
			)
			(fill no)
			(layer "F.CrtYd")
		)
		(fp_line
			(start 0.201 -0.202)
			(end -0.101 0)
			(stroke
				(width 0.15)
				(type solid)
			)
			(layer "F.Fab")
		)
		(fp_line
			(start -0.199 -0.202)
			(end -0.199 0.1)
			(stroke
				(width 0.15)
				(type solid)
			)
			(layer "F.Fab")
		)
		(fp_line
			(start 0.599 0)
			(end 0.201 0)
			(stroke
				(width 0.15)
				(type solid)
			)
			(layer "F.Fab")
		)
		(fp_line
			(start 0.201 0)
			(end 0.201 -0.202)
			(stroke
				(width 0.15)
				(type solid)
			)
			(layer "F.Fab")
		)
		(fp_line
			(start -0.101 0)
			(end 0.201 0.2)
			(stroke
				(width 0.15)
				(type solid)
			)
			(layer "F.Fab")
		)
		(fp_line
			(start -0.199 0)
			(end -0.597 0)
			(stroke
				(width 0.15)
				(type solid)
			)
			(layer "F.Fab")
		)
		(fp_line
			(start 0.201 0.2)
			(end 0.201 0)
			(stroke
				(width 0.15)
				(type solid)
			)
			(layer "F.Fab")
		)
		(fp_line
			(start -0.199 0.2)
			(end -0.199 0.1)
			(stroke
				(width 0.15)
				(type solid)
			)
			(layer "F.Fab")
		)
		(fp_rect
			(start 0.848 0.4)
			(end -0.85 -0.402)
			(stroke
				(width 0.15)
				(type solid)
			)
			(fill no)
			(layer "F.Fab")
		)
		(pad "1" smd roundrect
			(at -0.7 0 270)
			(size 0.8 1)
			(layers "F.Cu" "F.Mask" "F.Paste")
			(roundrect_rratio 0.2)
			(net 2 "GND")
			(pinfunction "C")
			(pintype "passive")
		)
		(pad "2" smd roundrect
			(at 0.7 0 270)
			(size 0.8 1)
			(layers "F.Cu" "F.Mask" "F.Paste")
			(roundrect_rratio 0.2)
			(net 64 "Net-(D3-A)")
			(pinfunction "A")
			(pintype "passive")
		)
	)
	(footprint "antmicro-footprints:QFN-24-1EP_4x4mm_P0.5_EP2.1x2.1mm"
		(layer "F.Cu")
		(at 85.6 73.4 -90)
		(property "Reference" "U1"
			(at -1.8228 2.4404 0)
			(layer "F.SilkS")
			(effects
				(font
					(size 0.7 0.7)
					(thickness 0.15)
				)
				(justify right bottom)
			)
		)
		(property "Value" "STUSB4500_QFN"
			(at 0 3.4 90)
			(layer "F.Fab")
			(effects
				(font
					(size 0.7 0.7)
					(thickness 0.15)
				)
				(justify right bottom)
			)
		)
		(property "Datasheet" "https://www.mouser.com/datasheet/2/389/dm00489312-1799262.pdf"
			(at 0 0 270)
			(layer "F.Fab")
			(hide yes)
			(effects
				(font
					(size 1.27 1.27)
					(thickness 0.15)
				)
			)
		)
		(property "Description" "USB Controller USB 2.0 I2C Interface 24-QFN (4x4)"
			(at 0 0 270)
			(layer "F.Fab")
			(hide yes)
			(effects
				(font
					(size 1.27 1.27)
					(thickness 0.15)
				)
			)
		)
		(property "MPN" "STUSB4500QTR"
			(at 0 0 270)
			(unlocked yes)
			(layer "F.Fab")
			(hide yes)
			(effects
				(font
					(size 1 1)
					(thickness 0.15)
				)
			)
		)
		(property "Manufacturer" "STMicroelectronics"
			(at 0 0 270)
			(unlocked yes)
			(layer "F.Fab")
			(hide yes)
			(effects
				(font
					(size 1 1)
					(thickness 0.15)
				)
			)
		)
		(property "Author" "Antmicro"
			(at 0 0 270)
			(unlocked yes)
			(layer "F.Fab")
			(hide yes)
			(effects
				(font
					(size 1 1)
					(thickness 0.15)
				)
			)
		)
		(property "License" "Apache-2.0"
			(at 0 0 270)
			(unlocked yes)
			(layer "F.Fab")
			(hide yes)
			(effects
				(font
					(size 1 1)
					(thickness 0.15)
				)
			)
		)
		(sheetname "/USB PD/")
		(sheetfile "usb_pd.kicad_sch")
		(attr smd)
		(fp_line
			(start -2.11 2.108)
			(end -2.11 1.634)
			(stroke
				(width 0.15)
				(type solid)
			)
			(layer "F.SilkS")
		)
		(fp_line
			(start -1.635 2.108)
			(end -2.11 2.108)
			(stroke
				(width 0.15)
				(type solid)
			)
			(layer "F.SilkS")
		)
		(fp_line
			(start 1.634 2.108)
			(end 2.108 2.108)
			(stroke
				(width 0.15)
				(type solid)
			)
			(layer "F.SilkS")
		)
		(fp_line
			(start 2.108 2.108)
			(end 2.108 1.634)
			(stroke
				(width 0.15)
				(type solid)
			)
			(layer "F.SilkS")
		)
		(fp_line
			(start -2.11 -1.636)
			(end -2.11 -2.11)
			(stroke
				(width 0.15)
				(type solid)
			)
			(layer "F.SilkS")
		)
		(fp_line
			(start -1.635 -2.11)
			(end -2.11 -2.11)
			(stroke
				(width 0.15)
				(type solid)
			)
			(layer "F.SilkS")
		)
		(fp_line
			(start 1.634 -2.11)
			(end 2.108 -2.11)
			(stroke
				(width 0.15)
				(type solid)
			)
			(layer "F.SilkS")
		)
		(fp_line
			(start 2.108 -2.11)
			(end 2.108 -1.635)
			(stroke
				(width 0.15)
				(type solid)
			)
			(layer "F.SilkS")
		)
		(fp_circle
			(center -2.3 -2.3)
			(end -2.25 -2.3)
			(stroke
				(width 0.15)
				(type solid)
			)
			(fill yes)
			(layer "F.SilkS")
		)
		(fp_rect
			(start -2.503 -2.503)
			(end 2.5 2.5)
			(stroke
				(width 0.05)
				(type solid)
			)
			(fill no)
			(layer "F.CrtYd")
		)
		(fp_line
			(start -2 1.999)
			(end -2 -1)
			(stroke
				(width 0.15)
				(type solid)
			)
			(layer "F.Fab")
		)
		(fp_line
			(start 1.999 1.999)
			(end -2 1.999)
			(stroke
				(width 0.15)
				(type solid)
			)
			(layer "F.Fab")
		)
		(fp_line
			(start -2 -1)
			(end -1 -2)
			(stroke
				(width 0.15)
				(type solid)
			)
			(layer "F.Fab")
		)
		(fp_line
			(start -1 -2)
			(end 1.999 -2)
			(stroke
				(width 0.15)
				(type solid)
			)
			(layer "F.Fab")
		)
		(fp_line
			(start 1.999 -2)
			(end 1.999 1.999)
			(stroke
				(width 0.15)
				(type solid)
			)
			(layer "F.Fab")
		)
		(pad "" smd roundrect
			(at -0.5 -0.5 270)
			(size 0.8 0.8)
			(layers "F.Paste")
			(roundrect_rratio 0.238095)
		)
		(pad "" smd roundrect
			(at -0.5 0.5 270)
			(size 0.8 0.8)
			(layers "F.Paste")
			(roundrect_rratio 0.238095)
		)
		(pad "" smd roundrect
			(at 0.5 -0.5 270)
			(size 0.8 0.8)
			(layers "F.Paste")
			(roundrect_rratio 0.238095)
		)
		(pad "" smd roundrect
			(at 0.5 0.5 270)
			(size 0.8 0.8)
			(layers "F.Paste")
			(roundrect_rratio 0.238095)
		)
		(pad "1" smd roundrect
			(at -1.938 -1.25 270)
			(size 0.825 0.25)
			(layers "F.Cu" "F.Mask" "F.Paste")
			(roundrect_rratio 0.25)
			(net 29 "/USB PD/CC1")
			(pinfunction "CC1DB")
			(pintype "bidirectional")
		)
		(pad "2" smd roundrect
			(at -1.938 -0.75 270)
			(size 0.825 0.25)
			(layers "F.Cu" "F.Mask" "F.Paste")
			(roundrect_rratio 0.25)
			(net 29 "/USB PD/CC1")
			(pinfunction "CC1")
			(pintype "bidirectional")
		)
		(pad "3" smd roundrect
			(at -1.938 -0.25 270)
			(size 0.825 0.25)
			(layers "F.Cu" "F.Mask" "F.Paste")
			(roundrect_rratio 0.25)
			(net 58 "unconnected-(U1-NC-Pad3)")
			(pinfunction "NC")
			(pintype "no_connect")
		)
		(pad "4" smd roundrect
			(at -1.938 0.248 270)
			(size 0.825 0.25)
			(layers "F.Cu" "F.Mask" "F.Paste")
			(roundrect_rratio 0.25)
			(net 33 "/USB PD/CC2")
			(pinfunction "CC2")
			(pintype "bidirectional")
		)
		(pad "5" smd roundrect
			(at -1.938 0.748 270)
			(size 0.825 0.25)
			(layers "F.Cu" "F.Mask" "F.Paste")
			(roundrect_rratio 0.25)
			(net 33 "/USB PD/CC2")
			(pinfunction "CC2DB")
			(pintype "bidirectional")
		)
		(pad "6" smd roundrect
			(at -1.938 1.249 270)
			(size 0.825 0.25)
			(layers "F.Cu" "F.Mask" "F.Paste")
			(roundrect_rratio 0.25)
			(net 42 "Net-(U1-RESET)")
			(pinfunction "RESET")
			(pintype "input")
		)
		(pad "7" smd roundrect
			(at -1.25 1.937 270)
			(size 0.25 0.825)
			(layers "F.Cu" "F.Mask" "F.Paste")
			(roundrect_rratio 0.25)
			(net 38 "/USB PD/SCL")
			(pinfunction "SCL")
			(pintype "input")
		)
		(pad "8" smd roundrect
			(at -0.75 1.937 270)
			(size 0.25 0.825)
			(layers "F.Cu" "F.Mask" "F.Paste")
			(roundrect_rratio 0.25)
			(net 37 "/USB PD/SDA")
			(pinfunction "SDA")
			(pintype "bidirectional")
		)
		(pad "9" smd roundrect
			(at -0.25 1.937 270)
			(size 0.25 0.825)
			(layers "F.Cu" "F.Mask" "F.Paste")
			(roundrect_rratio 0.25)
			(net 41 "Net-(U1-DISCH)")
			(pinfunction "DISCH")
			(pintype "bidirectional")
		)
		(pad "10" smd roundrect
			(at 0.248 1.937 270)
			(size 0.25 0.825)
			(layers "F.Cu" "F.Mask" "F.Paste")
			(roundrect_rratio 0.25)
			(net 2 "GND")
			(pinfunction "GND")
			(pintype "power_in")
		)
		(pad "11" smd roundrect
			(at 0.748 1.937 270)
			(size 0.25 0.825)
			(layers "F.Cu" "F.Mask" "F.Paste")
			(roundrect_rratio 0.25)
			(net 55 "Net-(U1-ATTACH)")
			(pinfunction "ATTACH")
			(pintype "output")
		)
		(pad "12" smd roundrect
			(at 1.249 1.937 270)
			(size 0.25 0.825)
			(layers "F.Cu" "F.Mask" "F.Paste")
			(roundrect_rratio 0.25)
			(net 2 "GND")
			(pinfunction "ADDR0")
			(pintype "input")
		)
		(pad "13" smd roundrect
			(at 1.937 1.249 270)
			(size 0.825 0.25)
			(layers "F.Cu" "F.Mask" "F.Paste")
			(roundrect_rratio 0.25)
			(net 2 "GND")
			(pinfunction "ADDR1")
			(pintype "input")
		)
		(pad "14" smd roundrect
			(at 1.937 0.748 270)
			(size 0.825 0.25)
			(layers "F.Cu" "F.Mask" "F.Paste")
			(roundrect_rratio 0.25)
			(net 28 "POWER_OK3")
			(pinfunction "POWER_OK3")
			(pintype "output")
		)
		(pad "15" smd roundrect
			(at 1.937 0.248 270)
			(size 0.825 0.25)
			(layers "F.Cu" "F.Mask" "F.Paste")
			(roundrect_rratio 0.25)
			(net 57 "Net-(U1-GPIO)")
			(pinfunction "GPIO")
			(pintype "output")
		)
		(pad "16" smd roundrect
			(at 1.937 -0.25 270)
			(size 0.825 0.25)
			(layers "F.Cu" "F.Mask" "F.Paste")
			(roundrect_rratio 0.25)
			(net 53 "/USB PD/VBUS_EN")
			(pinfunction "VBUS_EN_SNK")
			(pintype "output")
		)
		(pad "17" smd roundrect
			(at 1.937 -0.75 270)
			(size 0.825 0.25)
			(layers "F.Cu" "F.Mask" "F.Paste")
			(roundrect_rratio 0.25)
			(net 56 "Net-(U1-A_B_SIDE)")
			(pinfunction "A_B_SIDE")
			(pintype "output")
		)
		(pad "18" smd roundrect
			(at 1.937 -1.25 270)
			(size 0.825 0.25)
			(layers "F.Cu" "F.Mask" "F.Paste")
			(roundrect_rratio 0.25)
			(net 52 "/USB PD/VBUS_DISCH")
			(pinfunction "VBUS_VS_DISCH")
			(pintype "input")
		)
		(pad "19" smd roundrect
			(at 1.249 -1.938 270)
			(size 0.25 0.825)
			(layers "F.Cu" "F.Mask" "F.Paste")
			(roundrect_rratio 0.25)
			(net 54 "Net-(U1-~{ALERT})")
			(pinfunction "~{ALERT}")
			(pintype "output")
		)
		(pad "20" smd roundrect
			(at 0.748 -1.938 270)
			(size 0.25 0.825)
			(layers "F.Cu" "F.Mask" "F.Paste")
			(roundrect_rratio 0.25)
			(net 27 "POWER_OK2")
			(pinfunction "POWER_OK2")
			(pintype "output")
		)
		(pad "21" smd roundrect
			(at 0.248 -1.938 270)
			(size 0.25 0.825)
			(layers "F.Cu" "F.Mask" "F.Paste")
			(roundrect_rratio 0.25)
			(net 15 "Net-(U1-VREG_1V2)")
			(pinfunction "VREG_1V2")
			(pintype "output")
		)
		(pad "22" smd roundrect
			(at -0.25 -1.938 270)
			(size 0.25 0.825)
			(layers "F.Cu" "F.Mask" "F.Paste")
			(roundrect_rratio 0.25)
			(net 2 "GND")
			(pinfunction "VSYS")
			(pintype "power_in")
		)
		(pad "23" smd roundrect
			(at -0.75 -1.938 270)
			(size 0.25 0.825)
			(layers "F.Cu" "F.Mask" "F.Paste")
			(roundrect_rratio 0.25)
			(net 14 "Net-(U1-VREG_2V7)")
			(pinfunction "VREG_2V7")
			(pintype "output")
		)
		(pad "24" smd roundrect
			(at -1.25 -1.938 270)
			(size 0.25 0.825)
			(layers "F.Cu" "F.Mask" "F.Paste")
			(roundrect_rratio 0.25)
			(net 6 "VBUS")
			(pinfunction "VDD")
			(pintype "power_in")
		)
		(pad "25" smd rect
			(at 0 0 270)
			(size 2.1 2.1)
			(layers "F.Cu" "F.Mask")
			(net 2 "GND")
			(pinfunction "EP")
			(pintype "power_in")
		)
	)
	(footprint "antmicro-footprints:TP_SMD_0.75mm"
		(layer "F.Cu")
		(at 85.376 76.4)
		(property "Reference" "TP12"
			(at -6.858 -1.778 0)
			(layer "F.SilkS")
			(hide yes)
			(effects
				(font
					(size 0.7 0.7)
					(thickness 0.15)
				)
				(justify left bottom)
			)
		)
		(property "Value" "TP_0.75mm_SMD"
			(at 0 1.2 0)
			(layer "F.Fab")
			(effects
				(font
					(size 0.7 0.7)
					(thickness 0.15)
				)
				(justify left bottom)
			)
		)
		(property "Description" "SMT test point"
			(at 0 0 0)
			(layer "F.Fab")
			(hide yes)
			(effects
				(font
					(size 1.27 1.27)
					(thickness 0.15)
				)
			)
		)
		(property "MPN" ""
			(at 0 0 0)
			(unlocked yes)
			(layer "F.Fab")
			(hide yes)
			(effects
				(font
					(size 1 1)
					(thickness 0.15)
				)
			)
		)
		(property "Manufacturer" ""
			(at 0 0 0)
			(unlocked yes)
			(layer "F.Fab")
			(hide yes)
			(effects
				(font
					(size 1 1)
					(thickness 0.15)
				)
			)
		)
		(property "Author" "Antmicro"
			(at 0 0 0)
			(unlocked yes)
			(layer "F.Fab")
			(hide yes)
			(effects
				(font
					(size 1 1)
					(thickness 0.15)
				)
			)
		)
		(property "License" "Apache-2.0"
			(at 0 0 0)
			(unlocked yes)
			(layer "F.Fab")
			(hide yes)
			(effects
				(font
					(size 1 1)
					(thickness 0.15)
				)
			)
		)
		(sheetname "/USB PD/")
		(sheetfile "usb_pd.kicad_sch")
		(attr exclude_from_bom)
		(fp_circle
			(center 0 0)
			(end 0.475 0)
			(stroke
				(width 0.05)
				(type default)
			)
			(fill no)
			(layer "F.CrtYd")
		)
		(pad "1" smd circle
			(at 0 0)
			(size 0.75 0.75)
			(layers "F.Cu" "F.Mask")
			(net 57 "Net-(U1-GPIO)")
			(pinfunction "1")
			(pintype "passive")
		)
	)
	(footprint "antmicro-footprints:R_0402_1005Metric"
		(layer "F.Cu")
		(at 100 82.577 180)
		(descr "Resistor SMD 0402")
		(tags "resistor SMD 0402")
		(property "Reference" "R9"
			(at -1.092 -0.481 0)
			(layer "F.SilkS")
			(effects
				(font
					(size 0.7 0.7)
					(thickness 0.15)
				)
				(justify left bottom)
			)
		)
		(property "Value" "R_158k_0402"
			(at -1.011843 1.772047 0)
			(layer "F.Fab")
			(effects
				(font
					(size 0.7 0.7)
					(thickness 0.15)
				)
				(justify right bottom)
			)
		)
		(property "Datasheet" "https://www.bourns.com/docs/product-datasheets/cr.pdf"
			(at 0 0 180)
			(layer "F.Fab")
			(hide yes)
			(effects
				(font
					(size 1.27 1.27)
					(thickness 0.15)
				)
			)
		)
		(property "Description" "SMD Chip Resistor, 158 kohm, ± 1%, 100 mW, 0402 [1005 Metric], Thick Film, Precision"
			(at 0 0 180)
			(layer "F.Fab")
			(hide yes)
			(effects
				(font
					(size 1.27 1.27)
					(thickness 0.15)
				)
			)
		)
		(property "MPN" "CR0402-FX-1583GLF"
			(at 0 0 180)
			(unlocked yes)
			(layer "F.Fab")
			(hide yes)
			(effects
				(font
					(size 1 1)
					(thickness 0.15)
				)
			)
		)
		(property "Manufacturer" "Bourns"
			(at 0 0 180)
			(unlocked yes)
			(layer "F.Fab")
			(hide yes)
			(effects
				(font
					(size 1 1)
					(thickness 0.15)
				)
			)
		)
		(property "License" "Apache-2.0"
			(at 0 0 180)
			(unlocked yes)
			(layer "F.Fab")
			(hide yes)
			(effects
				(font
					(size 1 1)
					(thickness 0.15)
				)
			)
		)
		(property "Author" "Antmicro"
			(at 0 0 180)
			(unlocked yes)
			(layer "F.Fab")
			(hide yes)
			(effects
				(font
					(size 1 1)
					(thickness 0.15)
				)
			)
		)
		(property "Val" "158k"
			(at 0 0 180)
			(unlocked yes)
			(layer "F.Fab")
			(hide yes)
			(effects
				(font
					(size 1 1)
					(thickness 0.15)
				)
			)
		)
		(property "Tolerance" "1%"
			(at 0 0 180)
			(unlocked yes)
			(layer "F.Fab")
			(hide yes)
			(effects
				(font
					(size 1 1)
					(thickness 0.15)
				)
			)
		)
		(sheetname "/DC-DC Converters/")
		(sheetfile "dc-dc_converters.kicad_sch")
		(attr smd)
		(fp_rect
			(start -0.925 -0.47)
			(end 0.925 0.47)
			(stroke
				(width 0.05)
				(type default)
			)
			(fill no)
			(layer "F.CrtYd")
		)
		(fp_rect
			(start -0.5 -0.25)
			(end 0.5 0.25)
			(stroke
				(width 0.15)
				(type solid)
			)
			(fill no)
			(layer "F.Fab")
		)
		(pad "1" smd roundrect
			(at -0.48 0 180)
			(size 0.59 0.64)
			(layers "F.Cu" "F.Mask" "F.Paste")
			(roundrect_rratio 0.25)
			(net 2 "GND")
			(pintype "passive")
		)
		(pad "2" smd roundrect
			(at 0.48 0 180)
			(size 0.59 0.64)
			(layers "F.Cu" "F.Mask" "F.Paste")
			(roundrect_rratio 0.25)
			(net 46 "/DC-DC Converters/12V_FSW")
			(pintype "passive")
		)
	)
	(footprint "antmicro-footprints:R_0603_1608Metric"
		(layer "F.Cu")
		(at 82.45 79.45 90)
		(descr "Resistor SMD 0603")
		(tags "resistor SMD 0603")
		(property "Reference" "R3"
			(at 1.218 -0.662 180)
			(layer "F.SilkS")
			(effects
				(font
					(size 0.7 0.7)
					(thickness 0.15)
				)
				(justify left bottom)
			)
		)
		(property "Value" "R_4k7_0603"
			(at 0 1.6 90)
			(layer "F.Fab")
			(effects
				(font
					(size 0.7 0.7)
					(thickness 0.15)
				)
				(justify left bottom)
			)
		)
		(property "Datasheet" "https://www.bourns.com/docs/product-datasheets/cr.pdf"
			(at 0 0 90)
			(layer "F.Fab")
			(hide yes)
			(effects
				(font
					(size 1.27 1.27)
					(thickness 0.15)
				)
			)
		)
		(property "Description" "SMD Chip Resistor, 4.7 kohm, ± 1%, 100 mW, 0603 [1608 Metric], Thick Film, General Purpose"
			(at 0 0 90)
			(layer "F.Fab")
			(hide yes)
			(effects
				(font
					(size 1.27 1.27)
					(thickness 0.15)
				)
			)
		)
		(property "MPN" "CR0603-FX-4701ELF"
			(at 0 0 90)
			(unlocked yes)
			(layer "F.Fab")
			(hide yes)
			(effects
				(font
					(size 1 1)
					(thickness 0.15)
				)
			)
		)
		(property "Manufacturer" "Bourns"
			(at 0 0 90)
			(unlocked yes)
			(layer "F.Fab")
			(hide yes)
			(effects
				(font
					(size 1 1)
					(thickness 0.15)
				)
			)
		)
		(property "License" "Apache-2.0"
			(at 0 0 90)
			(unlocked yes)
			(layer "F.Fab")
			(hide yes)
			(effects
				(font
					(size 1 1)
					(thickness 0.15)
				)
			)
		)
		(property "Author" "Antmicro"
			(at 0 0 90)
			(unlocked yes)
			(layer "F.Fab")
			(hide yes)
			(effects
				(font
					(size 1 1)
					(thickness 0.15)
				)
			)
		)
		(property "Val" "4k7"
			(at 0 0 90)
			(unlocked yes)
			(layer "F.Fab")
			(hide yes)
			(effects
				(font
					(size 1 1)
					(thickness 0.15)
				)
			)
		)
		(property "Tolerance" "1%"
			(at 0 0 90)
			(unlocked yes)
			(layer "F.Fab")
			(hide yes)
			(effects
				(font
					(size 1 1)
					(thickness 0.15)
				)
			)
		)
		(sheetname "/USB PD/")
		(sheetfile "usb_pd.kicad_sch")
		(attr smd)
		(fp_line
			(start -0.15 -0.4)
			(end 0.15 -0.4)
			(stroke
				(width 0.15)
				(type solid)
			)
			(layer "F.SilkS")
		)
		(fp_line
			(start -0.15 0.4)
			(end 0.15 0.4)
			(stroke
				(width 0.15)
				(type solid)
			)
			(layer "F.SilkS")
		)
		(fp_rect
			(start -1.25 -0.65)
			(end 1.25 0.65)
			(stroke
				(width 0.05)
				(type solid)
			)
			(fill no)
			(layer "F.CrtYd")
		)
		(fp_rect
			(start -0.8 -0.4)
			(end 0.8 0.4)
			(stroke
				(width 0.15)
				(type solid)
			)
			(fill no)
			(layer "F.Fab")
		)
		(pad "1" smd roundrect
			(at -0.7 0 90)
			(size 0.8 1)
			(layers "F.Cu" "F.Mask" "F.Paste")
			(roundrect_rratio 0.2)
			(net 3 "VCC")
			(pintype "passive")
		)
		(pad "2" smd roundrect
			(at 0.7 0 90)
			(size 0.8 1)
			(layers "F.Cu" "F.Mask" "F.Paste")
			(roundrect_rratio 0.2)
			(net 41 "Net-(U1-DISCH)")
			(pintype "passive")
		)
	)
	(footprint "antmicro-footprints:LED_0603_1608Metric_G"
		(layer "F.Cu")
		(at 91.876 108.5 90)
		(descr "LED SMD 0603 Green")
		(tags "LED SMD 0603 Green")
		(property "Reference" "D4"
			(at 0.575 -0.775 90)
			(layer "F.SilkS")
			(effects
				(font
					(size 0.7 0.7)
					(thickness 0.15)
				)
				(justify right bottom)
			)
		)
		(property "Value" "LED_G_0603_LG_L29K-G2J1-24-Z"
			(at -0.001 1.599 90)
			(layer "F.Fab")
			(effects
				(font
					(size 0.7 0.7)
					(thickness 0.15)
				)
				(justify left bottom)
			)
		)
		(property "Datasheet" "https://look.ams-osram.com/m/19ee86b3ae0ee95b/original/LG-L29K.pdf"
			(at 0 0 90)
			(layer "F.Fab")
			(hide yes)
			(effects
				(font
					(size 1.27 1.27)
					(thickness 0.15)
				)
			)
		)
		(property "Description" "LED, Green, SMD, 0603, 20 mA, 1.7 V, 570 nm"
			(at 0 0 90)
			(layer "F.Fab")
			(hide yes)
			(effects
				(font
					(size 1.27 1.27)
					(thickness 0.15)
				)
			)
		)
		(property "MPN" "LG L29K-G2J1-24-Z"
			(at 0 0 90)
			(unlocked yes)
			(layer "F.Fab")
			(hide yes)
			(effects
				(font
					(size 1 1)
					(thickness 0.15)
				)
			)
		)
		(property "Manufacturer" "OSRAM"
			(at 0 0 90)
			(unlocked yes)
			(layer "F.Fab")
			(hide yes)
			(effects
				(font
					(size 1 1)
					(thickness 0.15)
				)
			)
		)
		(property "Color" "Green"
			(at 0 0 90)
			(unlocked yes)
			(layer "F.Fab")
			(hide yes)
			(effects
				(font
					(size 1 1)
					(thickness 0.15)
				)
			)
		)
		(property "Author" "Antmicro"
			(at 0 0 90)
			(unlocked yes)
			(layer "F.Fab")
			(hide yes)
			(effects
				(font
					(size 1 1)
					(thickness 0.15)
				)
			)
		)
		(property "License" "Apache-2.0"
			(at 0 0 90)
			(unlocked yes)
			(layer "F.Fab")
			(hide yes)
			(effects
				(font
					(size 1 1)
					(thickness 0.15)
				)
			)
		)
		(sheetname "/DC-DC Converters/")
		(sheetfile "dc-dc_converters.kicad_sch")
		(attr smd)
		(fp_line
			(start 0.22 -0.35)
			(end -0.22 -0.35)
			(stroke
				(width 0.15)
				(type solid)
			)
			(layer "F.SilkS")
		)
		(fp_line
			(start -1.18 -0.319)
			(end -1.18 0.321)
			(stroke
				(width 0.15)
				(type solid)
			)
			(layer "F.SilkS")
		)
		(fp_line
			(start 0.105328 0.001008)
			(end 0.24 0.001)
			(stroke
				(width 0.1)
				(type solid)
			)
			(layer "F.SilkS")
		)
		(fp_line
			(start -0.094672 0.001008)
			(end 0.105328 -0.198992)
			(stroke
				(width 0.1)
				(type solid)
			)
			(layer "F.SilkS")
		)
		(fp_line
			(start -0.094672 0.001008)
			(end -0.24 0.001008)
			(stroke
				(width 0.1)
				(type solid)
			)
			(layer "F.SilkS")
		)
		(fp_line
			(start 0.105328 0.201008)
			(end 0.105328 -0.198992)
			(stroke
				(width 0.1)
				(type solid)
			)
			(layer "F.SilkS")
		)
		(fp_line
			(start 0.105328 0.201008)
			(end -0.094672 0.001008)
			(stroke
				(width 0.1)
				(type solid)
			)
			(layer "F.SilkS")
		)
		(fp_line
			(start -0.094672 0.201008)
			(end -0.094672 -0.198992)
			(stroke
				(width 0.1)
				(type solid)
			)
			(layer "F.SilkS")
		)
		(fp_line
			(start 0.22 0.35)
			(end -0.22 0.35)
			(stroke
				(width 0.15)
				(type solid)
			)
			(layer "F.SilkS")
		)
		(fp_rect
			(start 1.25 0.65)
			(end -1.25 -0.65)
			(stroke
				(width 0.05)
				(type solid)
			)
			(fill no)
			(layer "F.CrtYd")
		)
		(fp_line
			(start 0.201 -0.202)
			(end -0.101 0)
			(stroke
				(width 0.15)
				(type solid)
			)
			(layer "F.Fab")
		)
		(fp_line
			(start -0.199 -0.202)
			(end -0.199 0.1)
			(stroke
				(width 0.15)
				(type solid)
			)
			(layer "F.Fab")
		)
		(fp_line
			(start 0.599 0)
			(end 0.201 0)
			(stroke
				(width 0.15)
				(type solid)
			)
			(layer "F.Fab")
		)
		(fp_line
			(start 0.201 0)
			(end 0.201 -0.202)
			(stroke
				(width 0.15)
				(type solid)
			)
			(layer "F.Fab")
		)
		(fp_line
			(start -0.101 0)
			(end 0.201 0.2)
			(stroke
				(width 0.15)
				(type solid)
			)
			(layer "F.Fab")
		)
		(fp_line
			(start -0.199 0)
			(end -0.597 0)
			(stroke
				(width 0.15)
				(type solid)
			)
			(layer "F.Fab")
		)
		(fp_line
			(start 0.201 0.2)
			(end 0.201 0)
			(stroke
				(width 0.15)
				(type solid)
			)
			(layer "F.Fab")
		)
		(fp_line
			(start -0.199 0.2)
			(end -0.199 0.1)
			(stroke
				(width 0.15)
				(type solid)
			)
			(layer "F.Fab")
		)
		(fp_rect
			(start 0.848 0.4)
			(end -0.85 -0.402)
			(stroke
				(width 0.15)
				(type solid)
			)
			(fill no)
			(layer "F.Fab")
		)
		(pad "1" smd roundrect
			(at -0.7 0 270)
			(size 0.8 1)
			(layers "F.Cu" "F.Mask" "F.Paste")
			(roundrect_rratio 0.2)
			(net 2 "GND")
			(pinfunction "C")
			(pintype "passive")
		)
		(pad "2" smd roundrect
			(at 0.7 0 270)
			(size 0.8 1)
			(layers "F.Cu" "F.Mask" "F.Paste")
			(roundrect_rratio 0.2)
			(net 65 "Net-(D4-A)")
			(pinfunction "A")
			(pintype "passive")
		)
	)
	(footprint "antmicro-footprints:LED_0603_1608Metric_G"
		(layer "F.Cu")
		(at 101.05 74.55 90)
		(descr "LED SMD 0603 Green")
		(tags "LED SMD 0603 Green")
		(property "Reference" "D8"
			(at -4.7 -2.574 0)
			(layer "B.SilkS")
			(effects
				(font
					(size 0.7 0.7)
					(thickness 0.15)
				)
				(justify right bottom mirror)
			)
		)
		(property "Value" "LED_G_0603_LG_L29K-G2J1-24-Z"
			(at -0.001 1.599 90)
			(layer "F.Fab")
			(effects
				(font
					(size 0.7 0.7)
					(thickness 0.15)
				)
				(justify left bottom)
			)
		)
		(property "Datasheet" "https://look.ams-osram.com/m/19ee86b3ae0ee95b/original/LG-L29K.pdf"
			(at 0 0 90)
			(layer "F.Fab")
			(hide yes)
			(effects
				(font
					(size 1.27 1.27)
					(thickness 0.15)
				)
			)
		)
		(property "Description" "LED, Green, SMD, 0603, 20 mA, 1.7 V, 570 nm"
			(at 0 0 90)
			(layer "F.Fab")
			(hide yes)
			(effects
				(font
					(size 1.27 1.27)
					(thickness 0.15)
				)
			)
		)
		(property "MPN" "LG L29K-G2J1-24-Z"
			(at 0 0 90)
			(unlocked yes)
			(layer "F.Fab")
			(hide yes)
			(effects
				(font
					(size 1 1)
					(thickness 0.15)
				)
			)
		)
		(property "Manufacturer" "OSRAM"
			(at 0 0 90)
			(unlocked yes)
			(layer "F.Fab")
			(hide yes)
			(effects
				(font
					(size 1 1)
					(thickness 0.15)
				)
			)
		)
		(property "Color" "Green"
			(at 0 0 90)
			(unlocked yes)
			(layer "F.Fab")
			(hide yes)
			(effects
				(font
					(size 1 1)
					(thickness 0.15)
				)
			)
		)
		(property "Author" "Antmicro"
			(at 0 0 90)
			(unlocked yes)
			(layer "F.Fab")
			(hide yes)
			(effects
				(font
					(size 1 1)
					(thickness 0.15)
				)
			)
		)
		(property "License" "Apache-2.0"
			(at 0 0 90)
			(unlocked yes)
			(layer "F.Fab")
			(hide yes)
			(effects
				(font
					(size 1 1)
					(thickness 0.15)
				)
			)
		)
		(sheetname "/DC-DC Converters/")
		(sheetfile "dc-dc_converters.kicad_sch")
		(attr smd)
		(fp_line
			(start 0.22 -0.35)
			(end -0.22 -0.35)
			(stroke
				(width 0.15)
				(type solid)
			)
			(layer "F.SilkS")
		)
		(fp_line
			(start -1.18 -0.319)
			(end -1.18 0.321)
			(stroke
				(width 0.15)
				(type solid)
			)
			(layer "F.SilkS")
		)
		(fp_line
			(start 0.105328 0.001008)
			(end 0.24 0.001)
			(stroke
				(width 0.1)
				(type solid)
			)
			(layer "F.SilkS")
		)
		(fp_line
			(start -0.094672 0.001008)
			(end 0.105328 -0.198992)
			(stroke
				(width 0.1)
				(type solid)
			)
			(layer "F.SilkS")
		)
		(fp_line
			(start -0.094672 0.001008)
			(end -0.24 0.001008)
			(stroke
				(width 0.1)
				(type solid)
			)
			(layer "F.SilkS")
		)
		(fp_line
			(start 0.105328 0.201008)
			(end 0.105328 -0.198992)
			(stroke
				(width 0.1)
				(type solid)
			)
			(layer "F.SilkS")
		)
		(fp_line
			(start 0.105328 0.201008)
			(end -0.094672 0.001008)
			(stroke
				(width 0.1)
				(type solid)
			)
			(layer "F.SilkS")
		)
		(fp_line
			(start -0.094672 0.201008)
			(end -0.094672 -0.198992)
			(stroke
				(width 0.1)
				(type solid)
			)
			(layer "F.SilkS")
		)
		(fp_line
			(start 0.22 0.35)
			(end -0.22 0.35)
			(stroke
				(width 0.15)
				(type solid)
			)
			(layer "F.SilkS")
		)
		(fp_rect
			(start 1.25 0.65)
			(end -1.25 -0.65)
			(stroke
				(width 0.05)
				(type solid)
			)
			(fill no)
			(layer "F.CrtYd")
		)
		(fp_line
			(start 0.201 -0.202)
			(end -0.101 0)
			(stroke
				(width 0.15)
				(type solid)
			)
			(layer "F.Fab")
		)
		(fp_line
			(start -0.199 -0.202)
			(end -0.199 0.1)
			(stroke
				(width 0.15)
				(type solid)
			)
			(layer "F.Fab")
		)
		(fp_line
			(start 0.599 0)
			(end 0.201 0)
			(stroke
				(width 0.15)
				(type solid)
			)
			(layer "F.Fab")
		)
		(fp_line
			(start 0.201 0)
			(end 0.201 -0.202)
			(stroke
				(width 0.15)
				(type solid)
			)
			(layer "F.Fab")
		)
		(fp_line
			(start -0.101 0)
			(end 0.201 0.2)
			(stroke
				(width 0.15)
				(type solid)
			)
			(layer "F.Fab")
		)
		(fp_line
			(start -0.199 0)
			(end -0.597 0)
			(stroke
				(width 0.15)
				(type solid)
			)
			(layer "F.Fab")
		)
		(fp_line
			(start 0.201 0.2)
			(end 0.201 0)
			(stroke
				(width 0.15)
				(type solid)
			)
			(layer "F.Fab")
		)
		(fp_line
			(start -0.199 0.2)
			(end -0.199 0.1)
			(stroke
				(width 0.15)
				(type solid)
			)
			(layer "F.Fab")
		)
		(fp_rect
			(start 0.848 0.4)
			(end -0.85 -0.402)
			(stroke
				(width 0.15)
				(type solid)
			)
			(fill no)
			(layer "F.Fab")
		)
		(pad "1" smd roundrect
			(at -0.7 0 270)
			(size 0.8 1)
			(layers "F.Cu" "F.Mask" "F.Paste")
			(roundrect_rratio 0.2)
			(net 2 "GND")
			(pinfunction "C")
			(pintype "passive")
		)
		(pad "2" smd roundrect
			(at 0.7 0 270)
			(size 0.8 1)
			(layers "F.Cu" "F.Mask" "F.Paste")
			(roundrect_rratio 0.2)
			(net 68 "Net-(D8-A)")
			(pinfunction "A")
			(pintype "passive")
		)
	)
	(footprint "antmicro-footprints:TP_SMD_0.75mm"
		(layer "F.Cu")
		(at 91.086 80.38)
		(property "Reference" "TP6"
			(at 14.076 -6.117 0)
			(layer "F.SilkS")
			(hide yes)
			(effects
				(font
					(size 0.7 0.7)
					(thickness 0.15)
				)
				(justify left bottom)
			)
		)
		(property "Value" "TP_0.75mm_SMD"
			(at 0 1.2 0)
			(layer "F.Fab")
			(effects
				(font
					(size 0.7 0.7)
					(thickness 0.15)
				)
				(justify left bottom)
			)
		)
		(property "Description" "SMT test point"
			(at 0 0 0)
			(layer "F.Fab")
			(hide yes)
			(effects
				(font
					(size 1.27 1.27)
					(thickness 0.15)
				)
			)
		)
		(property "MPN" ""
			(at 0 0 0)
			(unlocked yes)
			(layer "F.Fab")
			(hide yes)
			(effects
				(font
					(size 1 1)
					(thickness 0.15)
				)
			)
		)
		(property "Manufacturer" ""
			(at 0 0 0)
			(unlocked yes)
			(layer "F.Fab")
			(hide yes)
			(effects
				(font
					(size 1 1)
					(thickness 0.15)
				)
			)
		)
		(property "Author" "Antmicro"
			(at 0 0 0)
			(unlocked yes)
			(layer "F.Fab")
			(hide yes)
			(effects
				(font
					(size 1 1)
					(thickness 0.15)
				)
			)
		)
		(property "License" "Apache-2.0"
			(at 0 0 0)
			(unlocked yes)
			(layer "F.Fab")
			(hide yes)
			(effects
				(font
					(size 1 1)
					(thickness 0.15)
				)
			)
		)
		(sheetname "/DC-DC Converters/")
		(sheetfile "dc-dc_converters.kicad_sch")
		(attr exclude_from_bom)
		(fp_circle
			(center 0 0)
			(end 0.475 0)
			(stroke
				(width 0.05)
				(type default)
			)
			(fill no)
			(layer "F.CrtYd")
		)
		(pad "1" smd circle
			(at 0 0)
			(size 0.75 0.75)
			(layers "F.Cu" "F.Mask")
			(net 1 "+3V3")
			(pinfunction "1")
			(pintype "passive")
		)
	)
	(footprint "antmicro-footprints:C_0805_2012Metric"
		(layer "F.Cu")
		(at 91 84.7 90)
		(descr "Capacitor SMD 0805")
		(tags "capacitor SMD 0805")
		(property "Reference" "C3"
			(at -3.04 -5.854 90)
			(layer "F.SilkS")
			(effects
				(font
					(size 0.7 0.7)
					(thickness 0.15)
				)
				(justify left bottom)
			)
		)
		(property "Value" "C_10u_0805_35V"
			(at -2.055717 1.963152 90)
			(layer "F.Fab")
			(effects
				(font
					(size 0.7 0.7)
					(thickness 0.15)
				)
				(justify left bottom)
			)
		)
		(property "Datasheet" "https://www.murata.com/products/productdetail?partno=GRM21BR6YA106KE43%23"
			(at 0 0 90)
			(layer "F.Fab")
			(hide yes)
			(effects
				(font
					(size 1.27 1.27)
					(thickness 0.15)
				)
			)
		)
		(property "Description" "SMD Multilayer Ceramic Capacitor, 10 µF, 35 V, 0805 [2012 Metric], ± 10%, X5R, GRM Series"
			(at 0 0 90)
			(layer "F.Fab")
			(hide yes)
			(effects
				(font
					(size 1.27 1.27)
					(thickness 0.15)
				)
			)
		)
		(property "MPN" "GRM21BR6YA106KE43L"
			(at 0 0 90)
			(unlocked yes)
			(layer "F.Fab")
			(hide yes)
			(effects
				(font
					(size 1 1)
					(thickness 0.15)
				)
			)
		)
		(property "Manufacturer" "Murata"
			(at 0 0 90)
			(unlocked yes)
			(layer "F.Fab")
			(hide yes)
			(effects
				(font
					(size 1 1)
					(thickness 0.15)
				)
			)
		)
		(property "License" "Apache-2.0"
			(at 0 0 90)
			(unlocked yes)
			(layer "F.Fab")
			(hide yes)
			(effects
				(font
					(size 1 1)
					(thickness 0.15)
				)
			)
		)
		(property "Author" "Antmicro"
			(at 0 0 90)
			(unlocked yes)
			(layer "F.Fab")
			(hide yes)
			(effects
				(font
					(size 1 1)
					(thickness 0.15)
				)
			)
		)
		(property "Val" "10u"
			(at 0 0 90)
			(unlocked yes)
			(layer "F.Fab")
			(hide yes)
			(effects
				(font
					(size 1 1)
					(thickness 0.15)
				)
			)
		)
		(property "Voltage" "35V"
			(at 0 0 90)
			(unlocked yes)
			(layer "F.Fab")
			(hide yes)
			(effects
				(font
					(size 1 1)
					(thickness 0.15)
				)
			)
		)
		(property "Dielectric" ""
			(at 0 0 90)
			(unlocked yes)
			(layer "F.Fab")
			(hide yes)
			(effects
				(font
					(size 1 1)
					(thickness 0.15)
				)
			)
		)
		(property "Public" "False"
			(at 0 0 90)
			(unlocked yes)
			(layer "F.Fab")
			(hide yes)
			(effects
				(font
					(size 1 1)
					(thickness 0.15)
				)
			)
		)
		(sheetname "/DC-DC Converters/")
		(sheetfile "dc-dc_converters.kicad_sch")
		(attr smd)
		(fp_line
			(start -0.3 -0.7)
			(end 0.3 -0.7)
			(stroke
				(width 0.15)
				(type solid)
			)
			(layer "F.SilkS")
		)
		(fp_line
			(start -0.3 0.7)
			(end 0.3 0.7)
			(stroke
				(width 0.15)
				(type solid)
			)
			(layer "F.SilkS")
		)
		(fp_rect
			(start 1.95 -0.9)
			(end -1.95 0.9)
			(stroke
				(width 0.05)
				(type default)
			)
			(fill no)
			(layer "F.CrtYd")
		)
		(fp_rect
			(start -0.95 -0.675)
			(end 0.95 0.675)
			(stroke
				(width 0.15)
				(type solid)
			)
			(fill no)
			(layer "F.Fab")
		)
		(pad "1" smd roundrect
			(at -1.1 0 90)
			(size 1.2 1.3)
			(layers "F.Cu" "F.Mask" "F.Paste")
			(roundrect_rratio 0.25)
			(net 2 "GND")
			(pintype "passive")
		)
		(pad "2" smd roundrect
			(at 1.1 0 90)
			(size 1.2 1.3)
			(layers "F.Cu" "F.Mask" "F.Paste")
			(roundrect_rratio 0.25)
			(net 12 "Net-(U2-V_{CIN})")
			(pintype "passive")
		)
	)
	(footprint "antmicro-footprints:LED_0603_1608Metric_G"
		(layer "F.Cu")
		(at 102.4 74.55 90)
		(descr "LED SMD 0603 Green")
		(tags "LED SMD 0603 Green")
		(property "Reference" "D9"
			(at -3.7 -3.924 0)
			(layer "B.SilkS")
			(effects
				(font
					(size 0.7 0.7)
					(thickness 0.15)
				)
				(justify right bottom mirror)
			)
		)
		(property "Value" "LED_G_0603_LG_L29K-G2J1-24-Z"
			(at -0.001 1.599 90)
			(layer "F.Fab")
			(effects
				(font
					(size 0.7 0.7)
					(thickness 0.15)
				)
				(justify left bottom)
			)
		)
		(property "Datasheet" "https://look.ams-osram.com/m/19ee86b3ae0ee95b/original/LG-L29K.pdf"
			(at 0 0 90)
			(layer "F.Fab")
			(hide yes)
			(effects
				(font
					(size 1.27 1.27)
					(thickness 0.15)
				)
			)
		)
		(property "Description" "LED, Green, SMD, 0603, 20 mA, 1.7 V, 570 nm"
			(at 0 0 90)
			(layer "F.Fab")
			(hide yes)
			(effects
				(font
					(size 1.27 1.27)
					(thickness 0.15)
				)
			)
		)
		(property "MPN" "LG L29K-G2J1-24-Z"
			(at 0 0 90)
			(unlocked yes)
			(layer "F.Fab")
			(hide yes)
			(effects
				(font
					(size 1 1)
					(thickness 0.15)
				)
			)
		)
		(property "Manufacturer" "OSRAM"
			(at 0 0 90)
			(unlocked yes)
			(layer "F.Fab")
			(hide yes)
			(effects
				(font
					(size 1 1)
					(thickness 0.15)
				)
			)
		)
		(property "Color" "Green"
			(at 0 0 90)
			(unlocked yes)
			(layer "F.Fab")
			(hide yes)
			(effects
				(font
					(size 1 1)
					(thickness 0.15)
				)
			)
		)
		(property "Author" "Antmicro"
			(at 0 0 90)
			(unlocked yes)
			(layer "F.Fab")
			(hide yes)
			(effects
				(font
					(size 1 1)
					(thickness 0.15)
				)
			)
		)
		(property "License" "Apache-2.0"
			(at 0 0 90)
			(unlocked yes)
			(layer "F.Fab")
			(hide yes)
			(effects
				(font
					(size 1 1)
					(thickness 0.15)
				)
			)
		)
		(sheetname "/DC-DC Converters/")
		(sheetfile "dc-dc_converters.kicad_sch")
		(attr smd)
		(fp_line
			(start 0.22 -0.35)
			(end -0.22 -0.35)
			(stroke
				(width 0.15)
				(type solid)
			)
			(layer "F.SilkS")
		)
		(fp_line
			(start -1.18 -0.319)
			(end -1.18 0.321)
			(stroke
				(width 0.15)
				(type solid)
			)
			(layer "F.SilkS")
		)
		(fp_line
			(start 0.105328 0.001008)
			(end 0.24 0.001)
			(stroke
				(width 0.1)
				(type solid)
			)
			(layer "F.SilkS")
		)
		(fp_line
			(start -0.094672 0.001008)
			(end 0.105328 -0.198992)
			(stroke
				(width 0.1)
				(type solid)
			)
			(layer "F.SilkS")
		)
		(fp_line
			(start -0.094672 0.001008)
			(end -0.24 0.001008)
			(stroke
				(width 0.1)
				(type solid)
			)
			(layer "F.SilkS")
		)
		(fp_line
			(start 0.105328 0.201008)
			(end 0.105328 -0.198992)
			(stroke
				(width 0.1)
				(type solid)
			)
			(layer "F.SilkS")
		)
		(fp_line
			(start 0.105328 0.201008)
			(end -0.094672 0.001008)
			(stroke
				(width 0.1)
				(type solid)
			)
			(layer "F.SilkS")
		)
		(fp_line
			(start -0.094672 0.201008)
			(end -0.094672 -0.198992)
			(stroke
				(width 0.1)
				(type solid)
			)
			(layer "F.SilkS")
		)
		(fp_line
			(start 0.22 0.35)
			(end -0.22 0.35)
			(stroke
				(width 0.15)
				(type solid)
			)
			(layer "F.SilkS")
		)
		(fp_rect
			(start 1.25 0.65)
			(end -1.25 -0.65)
			(stroke
				(width 0.05)
				(type solid)
			)
			(fill no)
			(layer "F.CrtYd")
		)
		(fp_line
			(start 0.201 -0.202)
			(end -0.101 0)
			(stroke
				(width 0.15)
				(type solid)
			)
			(layer "F.Fab")
		)
		(fp_line
			(start -0.199 -0.202)
			(end -0.199 0.1)
			(stroke
				(width 0.15)
				(type solid)
			)
			(layer "F.Fab")
		)
		(fp_line
			(start 0.599 0)
			(end 0.201 0)
			(stroke
				(width 0.15)
				(type solid)
			)
			(layer "F.Fab")
		)
		(fp_line
			(start 0.201 0)
			(end 0.201 -0.202)
			(stroke
				(width 0.15)
				(type solid)
			)
			(layer "F.Fab")
		)
		(fp_line
			(start -0.101 0)
			(end 0.201 0.2)
			(stroke
				(width 0.15)
				(type solid)
			)
			(layer "F.Fab")
		)
		(fp_line
			(start -0.199 0)
			(end -0.597 0)
			(stroke
				(width 0.15)
				(type solid)
			)
			(layer "F.Fab")
		)
		(fp_line
			(start 0.201 0.2)
			(end 0.201 0)
			(stroke
				(width 0.15)
				(type solid)
			)
			(layer "F.Fab")
		)
		(fp_line
			(start -0.199 0.2)
			(end -0.199 0.1)
			(stroke
				(width 0.15)
				(type solid)
			)
			(layer "F.Fab")
		)
		(fp_rect
			(start 0.848 0.4)
			(end -0.85 -0.402)
			(stroke
				(width 0.15)
				(type solid)
			)
			(fill no)
			(layer "F.Fab")
		)
		(pad "1" smd roundrect
			(at -0.7 0 270)
			(size 0.8 1)
			(layers "F.Cu" "F.Mask" "F.Paste")
			(roundrect_rratio 0.2)
			(net 2 "GND")
			(pinfunction "C")
			(pintype "passive")
		)
		(pad "2" smd roundrect
			(at 0.7 0 270)
			(size 0.8 1)
			(layers "F.Cu" "F.Mask" "F.Paste")
			(roundrect_rratio 0.2)
			(net 69 "Net-(D9-A)")
			(pinfunction "A")
			(pintype "passive")
		)
	)
	(footprint "antmicro-footprints:LED_0603_1608Metric_G"
		(layer "F.Cu")
		(at 99.7 74.55 90)
		(descr "LED SMD 0603 Green")
		(tags "LED SMD 0603 Green")
		(property "Reference" "D7"
			(at -5.8 -1.224 0)
			(layer "B.SilkS")
			(effects
				(font
					(size 0.7 0.7)
					(thickness 0.15)
				)
				(justify right bottom mirror)
			)
		)
		(property "Value" "LED_G_0603_LG_L29K-G2J1-24-Z"
			(at -0.001 1.599 90)
			(layer "F.Fab")
			(effects
				(font
					(size 0.7 0.7)
					(thickness 0.15)
				)
				(justify left bottom)
			)
		)
		(property "Datasheet" "https://look.ams-osram.com/m/19ee86b3ae0ee95b/original/LG-L29K.pdf"
			(at 0 0 90)
			(layer "F.Fab")
			(hide yes)
			(effects
				(font
					(size 1.27 1.27)
					(thickness 0.15)
				)
			)
		)
		(property "Description" "LED, Green, SMD, 0603, 20 mA, 1.7 V, 570 nm"
			(at 0 0 90)
			(layer "F.Fab")
			(hide yes)
			(effects
				(font
					(size 1.27 1.27)
					(thickness 0.15)
				)
			)
		)
		(property "MPN" "LG L29K-G2J1-24-Z"
			(at 0 0 90)
			(unlocked yes)
			(layer "F.Fab")
			(hide yes)
			(effects
				(font
					(size 1 1)
					(thickness 0.15)
				)
			)
		)
		(property "Manufacturer" "OSRAM"
			(at 0 0 90)
			(unlocked yes)
			(layer "F.Fab")
			(hide yes)
			(effects
				(font
					(size 1 1)
					(thickness 0.15)
				)
			)
		)
		(property "Color" "Green"
			(at 0 0 90)
			(unlocked yes)
			(layer "F.Fab")
			(hide yes)
			(effects
				(font
					(size 1 1)
					(thickness 0.15)
				)
			)
		)
		(property "Author" "Antmicro"
			(at 0 0 90)
			(unlocked yes)
			(layer "F.Fab")
			(hide yes)
			(effects
				(font
					(size 1 1)
					(thickness 0.15)
				)
			)
		)
		(property "License" "Apache-2.0"
			(at 0 0 90)
			(unlocked yes)
			(layer "F.Fab")
			(hide yes)
			(effects
				(font
					(size 1 1)
					(thickness 0.15)
				)
			)
		)
		(sheetname "/USB PD/")
		(sheetfile "usb_pd.kicad_sch")
		(attr smd)
		(fp_line
			(start 0.22 -0.35)
			(end -0.22 -0.35)
			(stroke
				(width 0.15)
				(type solid)
			)
			(layer "F.SilkS")
		)
		(fp_line
			(start -1.18 -0.319)
			(end -1.18 0.321)
			(stroke
				(width 0.15)
				(type solid)
			)
			(layer "F.SilkS")
		)
		(fp_line
			(start 0.105328 0.001008)
			(end 0.24 0.001)
			(stroke
				(width 0.1)
				(type solid)
			)
			(layer "F.SilkS")
		)
		(fp_line
			(start -0.094672 0.001008)
			(end 0.105328 -0.198992)
			(stroke
				(width 0.1)
				(type solid)
			)
			(layer "F.SilkS")
		)
		(fp_line
			(start -0.094672 0.001008)
			(end -0.24 0.001008)
			(stroke
				(width 0.1)
				(type solid)
			)
			(layer "F.SilkS")
		)
		(fp_line
			(start 0.105328 0.201008)
			(end 0.105328 -0.198992)
			(stroke
				(width 0.1)
				(type solid)
			)
			(layer "F.SilkS")
		)
		(fp_line
			(start 0.105328 0.201008)
			(end -0.094672 0.001008)
			(stroke
				(width 0.1)
				(type solid)
			)
			(layer "F.SilkS")
		)
		(fp_line
			(start -0.094672 0.201008)
			(end -0.094672 -0.198992)
			(stroke
				(width 0.1)
				(type solid)
			)
			(layer "F.SilkS")
		)
		(fp_line
			(start 0.22 0.35)
			(end -0.22 0.35)
			(stroke
				(width 0.15)
				(type solid)
			)
			(layer "F.SilkS")
		)
		(fp_rect
			(start 1.25 0.65)
			(end -1.25 -0.65)
			(stroke
				(width 0.05)
				(type solid)
			)
			(fill no)
			(layer "F.CrtYd")
		)
		(fp_line
			(start 0.201 -0.202)
			(end -0.101 0)
			(stroke
				(width 0.15)
				(type solid)
			)
			(layer "F.Fab")
		)
		(fp_line
			(start -0.199 -0.202)
			(end -0.199 0.1)
			(stroke
				(width 0.15)
				(type solid)
			)
			(layer "F.Fab")
		)
		(fp_line
			(start 0.599 0)
			(end 0.201 0)
			(stroke
				(width 0.15)
				(type solid)
			)
			(layer "F.Fab")
		)
		(fp_line
			(start 0.201 0)
			(end 0.201 -0.202)
			(stroke
				(width 0.15)
				(type solid)
			)
			(layer "F.Fab")
		)
		(fp_line
			(start -0.101 0)
			(end 0.201 0.2)
			(stroke
				(width 0.15)
				(type solid)
			)
			(layer "F.Fab")
		)
		(fp_line
			(start -0.199 0)
			(end -0.597 0)
			(stroke
				(width 0.15)
				(type solid)
			)
			(layer "F.Fab")
		)
		(fp_line
			(start 0.201 0.2)
			(end 0.201 0)
			(stroke
				(width 0.15)
				(type solid)
			)
			(layer "F.Fab")
		)
		(fp_line
			(start -0.199 0.2)
			(end -0.199 0.1)
			(stroke
				(width 0.15)
				(type solid)
			)
			(layer "F.Fab")
		)
		(fp_rect
			(start 0.848 0.4)
			(end -0.85 -0.402)
			(stroke
				(width 0.15)
				(type solid)
			)
			(fill no)
			(layer "F.Fab")
		)
		(pad "1" smd roundrect
			(at -0.7 0 270)
			(size 0.8 1)
			(layers "F.Cu" "F.Mask" "F.Paste")
			(roundrect_rratio 0.2)
			(net 28 "POWER_OK3")
			(pinfunction "C")
			(pintype "passive")
		)
		(pad "2" smd roundrect
			(at 0.7 0 270)
			(size 0.8 1)
			(layers "F.Cu" "F.Mask" "F.Paste")
			(roundrect_rratio 0.2)
			(net 67 "Net-(D7-A)")
			(pinfunction "A")
			(pintype "passive")
		)
	)
	(footprint "antmicro-footprints:R_0402_1005Metric"
		(layer "F.Cu")
		(at 100 84.577)
		(descr "Resistor SMD 0402")
		(tags "resistor SMD 0402")
		(property "Reference" "R17"
			(at 1.092 0.513 0)
			(layer "F.SilkS")
			(effects
				(font
					(size 0.7 0.7)
					(thickness 0.15)
				)
				(justify left bottom)
			)
		)
		(property "Value" "R_140k_0.1%_0402"
			(at -1.011843 1.772047 0)
			(layer "F.Fab")
			(effects
				(font
					(size 0.7 0.7)
					(thickness 0.15)
				)
				(justify left bottom)
			)
		)
		(property "Datasheet" "https://www.vishay.com/docs/28758/tnpw_e3.pdf"
			(at 0 0 0)
			(layer "F.Fab")
			(hide yes)
			(effects
				(font
					(size 1.27 1.27)
					(thickness 0.15)
				)
			)
		)
		(property "Description" "SMD Chip Resistor, Ceramic, 140 kohm, ± 0.1%, 62.5 mW, 0402 [1005 Metric], Thin Film, Precision resistors"
			(at 0 0 0)
			(layer "F.Fab")
			(hide yes)
			(effects
				(font
					(size 1.27 1.27)
					(thickness 0.15)
				)
			)
		)
		(property "MPN" "RT0402BRD07140KL"
			(at 0 0 0)
			(unlocked yes)
			(layer "F.Fab")
			(hide yes)
			(effects
				(font
					(size 1 1)
					(thickness 0.15)
				)
			)
		)
		(property "Val" "140k"
			(at 0 0 0)
			(unlocked yes)
			(layer "F.Fab")
			(hide yes)
			(effects
				(font
					(size 1 1)
					(thickness 0.15)
				)
			)
		)
		(property "Manufacturer" "YAGEO"
			(at 0 0 0)
			(unlocked yes)
			(layer "F.Fab")
			(hide yes)
			(effects
				(font
					(size 1 1)
					(thickness 0.15)
				)
			)
		)
		(property "Tolerance" "0.1%"
			(at 0 0 0)
			(unlocked yes)
			(layer "F.Fab")
			(hide yes)
			(effects
				(font
					(size 1 1)
					(thickness 0.15)
				)
			)
		)
		(property "License" "Apache-2.0"
			(at 0 0 0)
			(unlocked yes)
			(layer "F.Fab")
			(hide yes)
			(effects
				(font
					(size 1 1)
					(thickness 0.15)
				)
			)
		)
		(property "Author" "Antmicro"
			(at 0 0 0)
			(unlocked yes)
			(layer "F.Fab")
			(hide yes)
			(effects
				(font
					(size 1 1)
					(thickness 0.15)
				)
			)
		)
		(sheetname "/DC-DC Converters/")
		(sheetfile "dc-dc_converters.kicad_sch")
		(attr smd)
		(fp_rect
			(start -0.925 -0.47)
			(end 0.925 0.47)
			(stroke
				(width 0.05)
				(type default)
			)
			(fill no)
			(layer "F.CrtYd")
		)
		(fp_rect
			(start -0.5 -0.25)
			(end 0.5 0.25)
			(stroke
				(width 0.15)
				(type solid)
			)
			(fill no)
			(layer "F.Fab")
		)
		(pad "1" smd roundrect
			(at -0.48 0)
			(size 0.59 0.64)
			(layers "F.Cu" "F.Mask" "F.Paste")
			(roundrect_rratio 0.25)
			(net 51 "Net-(U2-V_{FB})")
			(pintype "passive")
		)
		(pad "2" smd roundrect
			(at 0.48 0)
			(size 0.59 0.64)
			(layers "F.Cu" "F.Mask" "F.Paste")
			(roundrect_rratio 0.25)
			(net 5 "+12V")
			(pintype "passive")
		)
	)
	(footprint "antmicro-footprints:R_0402_1005Metric"
		(layer "F.Cu")
		(at 83.35 69.75 90)
		(descr "Resistor SMD 0402")
		(tags "resistor SMD 0402")
		(property "Reference" "R31"
			(at 1.17 0.47 90)
			(layer "F.SilkS")
			(effects
				(font
					(size 0.7 0.7)
					(thickness 0.15)
				)
				(justify left bottom)
			)
		)
		(property "Value" "R_4k7_0402"
			(at -1.011843 1.772047 90)
			(layer "F.Fab")
			(effects
				(font
					(size 0.7 0.7)
					(thickness 0.15)
				)
				(justify left bottom)
			)
		)
		(property "Datasheet" "https://www.bourns.com/docs/product-datasheets/cr.pdf"
			(at 0 0 90)
			(layer "F.Fab")
			(hide yes)
			(effects
				(font
					(size 1.27 1.27)
					(thickness 0.15)
				)
			)
		)
		(property "Description" "SMD Chip Resistor, 4.7 kohm, ± 1%, 62.5 mW, 0402 [1005 Metric], Thick Film, General Purpose"
			(at 0 0 90)
			(layer "F.Fab")
			(hide yes)
			(effects
				(font
					(size 1.27 1.27)
					(thickness 0.15)
				)
			)
		)
		(property "MPN" "CR0402-FX-4701GLF"
			(at 0 0 90)
			(unlocked yes)
			(layer "F.Fab")
			(hide yes)
			(effects
				(font
					(size 1 1)
					(thickness 0.15)
				)
			)
		)
		(property "Manufacturer" "Bourns"
			(at 0 0 90)
			(unlocked yes)
			(layer "F.Fab")
			(hide yes)
			(effects
				(font
					(size 1 1)
					(thickness 0.15)
				)
			)
		)
		(property "License" "Apache-2.0"
			(at 0 0 90)
			(unlocked yes)
			(layer "F.Fab")
			(hide yes)
			(effects
				(font
					(size 1 1)
					(thickness 0.15)
				)
			)
		)
		(property "Author" "Antmicro"
			(at 0 0 90)
			(unlocked yes)
			(layer "F.Fab")
			(hide yes)
			(effects
				(font
					(size 1 1)
					(thickness 0.15)
				)
			)
		)
		(property "Val" "4k7"
			(at 0 0 90)
			(unlocked yes)
			(layer "F.Fab")
			(hide yes)
			(effects
				(font
					(size 1 1)
					(thickness 0.15)
				)
			)
		)
		(property "Tolerance" "1%"
			(at 0 0 90)
			(unlocked yes)
			(layer "F.Fab")
			(hide yes)
			(effects
				(font
					(size 1 1)
					(thickness 0.15)
				)
			)
		)
		(sheetname "/USB PD/")
		(sheetfile "usb_pd.kicad_sch")
		(attr smd exclude_from_pos_files exclude_from_bom dnp)
		(fp_rect
			(start -0.925 -0.47)
			(end 0.925 0.47)
			(stroke
				(width 0.05)
				(type default)
			)
			(fill no)
			(layer "F.CrtYd")
		)
		(fp_rect
			(start -0.5 -0.25)
			(end 0.5 0.25)
			(stroke
				(width 0.15)
				(type solid)
			)
			(fill no)
			(layer "F.Fab")
		)
		(pad "1" smd roundrect
			(at -0.48 0 90)
			(size 0.59 0.64)
			(layers "F.Cu" "F.Mask" "F.Paste")
			(roundrect_rratio 0.25)
			(net 38 "/USB PD/SCL")
			(pintype "passive")
		)
		(pad "2" smd roundrect
			(at 0.48 0 90)
			(size 0.59 0.64)
			(layers "F.Cu" "F.Mask" "F.Paste")
			(roundrect_rratio 0.25)
			(net 1 "+3V3")
			(pintype "passive")
		)
	)
	(footprint "antmicro-footprints:TP_SMD_0.75mm"
		(layer "F.Cu")
		(at 88.601 75.125)
		(property "Reference" "TP9"
			(at 5.684 -5.15 0)
			(layer "F.SilkS")
			(hide yes)
			(effects
				(font
					(size 0.7 0.7)
					(thickness 0.15)
				)
				(justify left bottom)
			)
		)
		(property "Value" "TP_0.75mm_SMD"
			(at 0 1.2 0)
			(layer "F.Fab")
			(effects
				(font
					(size 0.7 0.7)
					(thickness 0.15)
				)
				(justify left bottom)
			)
		)
		(property "Description" "SMT test point"
			(at 0 0 0)
			(layer "F.Fab")
			(hide yes)
			(effects
				(font
					(size 1.27 1.27)
					(thickness 0.15)
				)
			)
		)
		(property "MPN" ""
			(at 0 0 0)
			(unlocked yes)
			(layer "F.Fab")
			(hide yes)
			(effects
				(font
					(size 1 1)
					(thickness 0.15)
				)
			)
		)
		(property "Manufacturer" ""
			(at 0 0 0)
			(unlocked yes)
			(layer "F.Fab")
			(hide yes)
			(effects
				(font
					(size 1 1)
					(thickness 0.15)
				)
			)
		)
		(property "Author" "Antmicro"
			(at 0 0 0)
			(unlocked yes)
			(layer "F.Fab")
			(hide yes)
			(effects
				(font
					(size 1 1)
					(thickness 0.15)
				)
			)
		)
		(property "License" "Apache-2.0"
			(at 0 0 0)
			(unlocked yes)
			(layer "F.Fab")
			(hide yes)
			(effects
				(font
					(size 1 1)
					(thickness 0.15)
				)
			)
		)
		(sheetname "/USB PD/")
		(sheetfile "usb_pd.kicad_sch")
		(attr exclude_from_bom)
		(fp_circle
			(center 0 0)
			(end 0.475 0)
			(stroke
				(width 0.05)
				(type default)
			)
			(fill no)
			(layer "F.CrtYd")
		)
		(pad "1" smd circle
			(at 0 0)
			(size 0.75 0.75)
			(layers "F.Cu" "F.Mask")
			(net 54 "Net-(U1-~{ALERT})")
			(pinfunction "1")
			(pintype "passive")
		)
	)
	(footprint "antmicro-footprints:TP_SMD_0.75mm"
		(layer "F.Cu")
		(at 82.696 75.36 180)
		(property "Reference" "TP8"
			(at 1.9812 -1.5748 90)
			(layer "F.SilkS")
			(hide yes)
			(effects
				(font
					(size 0.7 0.7)
					(thickness 0.15)
				)
				(justify left bottom)
			)
		)
		(property "Value" "TP_0.75mm_SMD"
			(at 0 1.2 0)
			(layer "F.Fab")
			(effects
				(font
					(size 0.7 0.7)
					(thickness 0.15)
				)
				(justify right bottom)
			)
		)
		(property "Description" "SMT test point"
			(at 0 0 180)
			(layer "F.Fab")
			(hide yes)
			(effects
				(font
					(size 1.27 1.27)
					(thickness 0.15)
				)
			)
		)
		(property "MPN" ""
			(at 0 0 180)
			(unlocked yes)
			(layer "F.Fab")
			(hide yes)
			(effects
				(font
					(size 1 1)
					(thickness 0.15)
				)
			)
		)
		(property "Manufacturer" ""
			(at 0 0 180)
			(unlocked yes)
			(layer "F.Fab")
			(hide yes)
			(effects
				(font
					(size 1 1)
					(thickness 0.15)
				)
			)
		)
		(property "Author" "Antmicro"
			(at 0 0 180)
			(unlocked yes)
			(layer "F.Fab")
			(hide yes)
			(effects
				(font
					(size 1 1)
					(thickness 0.15)
				)
			)
		)
		(property "License" "Apache-2.0"
			(at 0 0 180)
			(unlocked yes)
			(layer "F.Fab")
			(hide yes)
			(effects
				(font
					(size 1 1)
					(thickness 0.15)
				)
			)
		)
		(sheetname "/USB PD/")
		(sheetfile "usb_pd.kicad_sch")
		(attr exclude_from_bom)
		(fp_circle
			(center 0 0)
			(end 0.475 0)
			(stroke
				(width 0.05)
				(type default)
			)
			(fill no)
			(layer "F.CrtYd")
		)
		(pad "1" smd circle
			(at 0 0 180)
			(size 0.75 0.75)
			(layers "F.Cu" "F.Mask")
			(net 42 "Net-(U1-RESET)")
			(pinfunction "1")
			(pintype "passive")
		)
	)
	(footprint "antmicro-footprints:R_0402_1005Metric"
		(layer "F.Cu")
		(at 92.776 80.3 90)
		(descr "Resistor SMD 0402")
		(tags "resistor SMD 0402")
		(property "Reference" "R20"
			(at 1.05 10.05 0)
			(layer "B.SilkS")
			(effects
				(font
					(size 0.7 0.7)
					(thickness 0.15)
				)
				(justify left bottom mirror)
			)
		)
		(property "Value" "R_1k_0402"
			(at -1.011843 1.772047 90)
			(layer "F.Fab")
			(effects
				(font
					(size 0.7 0.7)
					(thickness 0.15)
				)
				(justify left bottom)
			)
		)
		(property "Datasheet" "https://www.bourns.com/docs/product-datasheets/cr.pdf"
			(at 0 0 90)
			(layer "F.Fab")
			(hide yes)
			(effects
				(font
					(size 1.27 1.27)
					(thickness 0.15)
				)
			)
		)
		(property "Description" "SMD Chip Resistor, 1 kohm, ± 1%, 63 mW, 0402 [1005 Metric], Thick Film, General Purpose"
			(at 0 0 90)
			(layer "F.Fab")
			(hide yes)
			(effects
				(font
					(size 1.27 1.27)
					(thickness 0.15)
				)
			)
		)
		(property "MPN" "CR0402-FX-1001GLF"
			(at 0 0 90)
			(unlocked yes)
			(layer "F.Fab")
			(hide yes)
			(effects
				(font
					(size 1 1)
					(thickness 0.15)
				)
			)
		)
		(property "Manufacturer" "Bourns"
			(at 0 0 90)
			(unlocked yes)
			(layer "F.Fab")
			(hide yes)
			(effects
				(font
					(size 1 1)
					(thickness 0.15)
				)
			)
		)
		(property "License" "Apache-2.0"
			(at 0 0 90)
			(unlocked yes)
			(layer "F.Fab")
			(hide yes)
			(effects
				(font
					(size 1 1)
					(thickness 0.15)
				)
			)
		)
		(property "Author" "Antmicro"
			(at 0 0 90)
			(unlocked yes)
			(layer "F.Fab")
			(hide yes)
			(effects
				(font
					(size 1 1)
					(thickness 0.15)
				)
			)
		)
		(property "Val" "1k"
			(at 0 0 90)
			(unlocked yes)
			(layer "F.Fab")
			(hide yes)
			(effects
				(font
					(size 1 1)
					(thickness 0.15)
				)
			)
		)
		(property "Tolerance" "1%"
			(at 0 0 90)
			(unlocked yes)
			(layer "F.Fab")
			(hide yes)
			(effects
				(font
					(size 1 1)
					(thickness 0.15)
				)
			)
		)
		(sheetname "/USB PD/")
		(sheetfile "usb_pd.kicad_sch")
		(attr smd)
		(fp_rect
			(start -0.925 -0.47)
			(end 0.925 0.47)
			(stroke
				(width 0.05)
				(type default)
			)
			(fill no)
			(layer "F.CrtYd")
		)
		(fp_rect
			(start -0.5 -0.25)
			(end 0.5 0.25)
			(stroke
				(width 0.15)
				(type solid)
			)
			(fill no)
			(layer "F.Fab")
		)
		(pad "1" smd roundrect
			(at -0.48 0 90)
			(size 0.59 0.64)
			(layers "F.Cu" "F.Mask" "F.Paste")
			(roundrect_rratio 0.25)
			(net 52 "/USB PD/VBUS_DISCH")
			(pintype "passive")
		)
		(pad "2" smd roundrect
			(at 0.48 0 90)
			(size 0.59 0.64)
			(layers "F.Cu" "F.Mask" "F.Paste")
			(roundrect_rratio 0.25)
			(net 63 "Net-(D1-C)")
			(pintype "passive")
		)
	)
	(footprint "antmicro-footprints:USON-10_2.5x1mm_P0.5mm"
		(layer "F.Cu")
		(at 86.9 68.6 90)
		(descr "USON-10 2.5x1mm_ Pitch 0.5mm")
		(tags "USON-10 2.5x1mm Pitch 0.5mm")
		(property "Reference" "U6"
			(at 0.8836 -1.1496 180)
			(layer "F.SilkS")
			(effects
				(font
					(size 0.7 0.7)
					(thickness 0.15)
				)
				(justify left bottom)
			)
		)
		(property "Value" "TPD4E02B04DQA"
			(at 0.018 2.499 90)
			(layer "F.Fab")
			(effects
				(font
					(size 0.7 0.7)
					(thickness 0.15)
				)
				(justify left bottom)
			)
		)
		(property "Datasheet" "http://www.ti.com/lit/ds/symlink/tpd4e02b04.pdf"
			(at 0 0 90)
			(layer "F.Fab")
			(hide yes)
			(effects
				(font
					(size 1.27 1.27)
					(thickness 0.15)
				)
			)
		)
		(property "Description" "TVS diode array, 12 kV, USON-10, 3.6 V, 0.33 pF"
			(at 0 0 90)
			(layer "F.Fab")
			(hide yes)
			(effects
				(font
					(size 1.27 1.27)
					(thickness 0.15)
				)
			)
		)
		(property "MPN" "TPD4E02B04DQAR"
			(at 0 0 90)
			(unlocked yes)
			(layer "F.Fab")
			(hide yes)
			(effects
				(font
					(size 1 1)
					(thickness 0.15)
				)
			)
		)
		(property "Manufacturer" "Texas Instruments"
			(at 0 0 90)
			(unlocked yes)
			(layer "F.Fab")
			(hide yes)
			(effects
				(font
					(size 1 1)
					(thickness 0.15)
				)
			)
		)
		(property "Author" "Antmicro"
			(at 0 0 90)
			(unlocked yes)
			(layer "F.Fab")
			(hide yes)
			(effects
				(font
					(size 1 1)
					(thickness 0.15)
				)
			)
		)
		(property "License" "Apache-2.0"
			(at 0 0 90)
			(unlocked yes)
			(layer "F.Fab")
			(hide yes)
			(effects
				(font
					(size 1 1)
					(thickness 0.15)
				)
			)
		)
		(property ki_fp_filters "USON*2.5x1.0mm*P0.5mm*")
		(sheetname "/USB PD/")
		(sheetfile "usb_pd.kicad_sch")
		(attr smd)
		(fp_line
			(start 0.498 -1.401)
			(end -0.5 -1.401)
			(stroke
				(width 0.15)
				(type solid)
			)
			(layer "F.SilkS")
		)
		(fp_line
			(start 0.498 1.398)
			(end -0.5 1.398)
			(stroke
				(width 0.15)
				(type solid)
			)
			(layer "F.SilkS")
		)
		(fp_circle
			(center -0.68 -1.27)
			(end -0.63 -1.27)
			(stroke
				(width 0.15)
				(type solid)
			)
			(fill yes)
			(layer "F.SilkS")
		)
		(fp_rect
			(start -0.8 -1.5)
			(end 0.8 1.499)
			(stroke
				(width 0.05)
				(type solid)
			)
			(fill no)
			(layer "F.CrtYd")
		)
		(fp_line
			(start 0.498 -1.25)
			(end -0.25 -1.25)
			(stroke
				(width 0.15)
				(type solid)
			)
			(layer "F.Fab")
		)
		(fp_line
			(start 0.498 -1.25)
			(end 0.498 1.249)
			(stroke
				(width 0.15)
				(type solid)
			)
			(layer "F.Fab")
		)
		(fp_line
			(start -0.25 -1.25)
			(end -0.5 -1)
			(stroke
				(width 0.15)
				(type solid)
			)
			(layer "F.Fab")
		)
		(fp_line
			(start -0.5 -1)
			(end -0.5 1.249)
			(stroke
				(width 0.15)
				(type solid)
			)
			(layer "F.Fab")
		)
		(fp_line
			(start -0.5 1.249)
			(end 0.498 1.249)
			(stroke
				(width 0.15)
				(type solid)
			)
			(layer "F.Fab")
		)
		(pad "1" smd roundrect
			(at -0.387 -1)
			(size 0.25 0.55)
			(layers "F.Cu" "F.Mask" "F.Paste")
			(roundrect_rratio 0.25)
			(net 70 "unconnected-(U6-Pad1)_1")
			(pintype "passive+no_connect")
		)
		(pad "2" smd roundrect
			(at -0.387 -0.5)
			(size 0.25 0.55)
			(layers "F.Cu" "F.Mask" "F.Paste")
			(roundrect_rratio 0.25)
			(net 38 "/USB PD/SCL")
			(pintype "passive")
		)
		(pad "3" smd roundrect
			(at -0.387 0)
			(size 0.4 0.55)
			(layers "F.Cu" "F.Mask" "F.Paste")
			(roundrect_rratio 0.25)
			(net 2 "GND")
			(pintype "power_in")
		)
		(pad "4" smd roundrect
			(at -0.387 0.498)
			(size 0.25 0.55)
			(layers "F.Cu" "F.Mask" "F.Paste")
			(roundrect_rratio 0.25)
			(net 37 "/USB PD/SDA")
			(pintype "passive")
		)
		(pad "5" smd roundrect
			(at -0.387 0.998)
			(size 0.25 0.55)
			(layers "F.Cu" "F.Mask" "F.Paste")
			(roundrect_rratio 0.25)
			(net 61 "/USB PD/QWIIC_VCC")
			(pintype "passive")
		)
		(pad "6" smd roundrect
			(at 0.385 0.998)
			(size 0.25 0.55)
			(layers "F.Cu" "F.Mask" "F.Paste")
			(roundrect_rratio 0.25)
			(net 61 "/USB PD/QWIIC_VCC")
			(pintype "passive")
		)
		(pad "7" smd roundrect
			(at 0.385 0.498)
			(size 0.25 0.55)
			(layers "F.Cu" "F.Mask" "F.Paste")
			(roundrect_rratio 0.25)
			(net 37 "/USB PD/SDA")
			(pintype "passive")
		)
		(pad "8" smd roundrect
			(at 0.385 0)
			(size 0.4 0.55)
			(layers "F.Cu" "F.Mask" "F.Paste")
			(roundrect_rratio 0.25)
			(net 2 "GND")
			(pintype "passive")
		)
		(pad "9" smd roundrect
			(at 0.385 -0.5)
			(size 0.25 0.55)
			(layers "F.Cu" "F.Mask" "F.Paste")
			(roundrect_rratio 0.25)
			(net 38 "/USB PD/SCL")
			(pintype "passive")
		)
		(pad "10" smd roundrect
			(at 0.385 -1)
			(size 0.25 0.55)
			(layers "F.Cu" "F.Mask" "F.Paste")
			(roundrect_rratio 0.25)
			(net 62 "unconnected-(U6-Pad1)")
			(pintype "passive+no_connect")
		)
	)
	(footprint "antmicro-footprints:TP_SMD_0.75mm"
		(layer "F.Cu")
		(at 87.801 87.225)
		(property "Reference" "TP13"
			(at 0 -0.6 0)
			(layer "F.SilkS")
			(hide yes)
			(effects
				(font
					(size 0.7 0.7)
					(thickness 0.15)
				)
				(justify left bottom)
			)
		)
		(property "Value" "TP_0.75mm_SMD"
			(at 0 1.2 0)
			(layer "F.Fab")
			(effects
				(font
					(size 0.7 0.7)
					(thickness 0.15)
				)
				(justify left bottom)
			)
		)
		(property "Description" "SMT test point"
			(at 0 0 0)
			(layer "F.Fab")
			(hide yes)
			(effects
				(font
					(size 1.27 1.27)
					(thickness 0.15)
				)
			)
		)
		(property "MPN" ""
			(at 0 0 0)
			(unlocked yes)
			(layer "F.Fab")
			(hide yes)
			(effects
				(font
					(size 1 1)
					(thickness 0.15)
				)
			)
		)
		(property "Manufacturer" ""
			(at 0 0 0)
			(unlocked yes)
			(layer "F.Fab")
			(hide yes)
			(effects
				(font
					(size 1 1)
					(thickness 0.15)
				)
			)
		)
		(property "Author" "Antmicro"
			(at 0 0 0)
			(unlocked yes)
			(layer "F.Fab")
			(hide yes)
			(effects
				(font
					(size 1 1)
					(thickness 0.15)
				)
			)
		)
		(property "License" "Apache-2.0"
			(at 0 0 0)
			(unlocked yes)
			(layer "F.Fab")
			(hide yes)
			(effects
				(font
					(size 1 1)
					(thickness 0.15)
				)
			)
		)
		(sheetname "/USB PD/")
		(sheetfile "usb_pd.kicad_sch")
		(attr exclude_from_bom)
		(fp_circle
			(center 0 0)
			(end 0.475 0)
			(stroke
				(width 0.05)
				(type default)
			)
			(fill no)
			(layer "F.CrtYd")
		)
		(pad "1" smd circle
			(at 0 0)
			(size 0.75 0.75)
			(layers "F.Cu" "F.Mask")
			(net 2 "GND")
			(pinfunction "1")
			(pintype "passive")
		)
	)
	(footprint "antmicro-footprints:R_0402_1005Metric"
		(layer "F.Cu")
		(at 95.8 80.3 90)
		(descr "Resistor SMD 0402")
		(tags "resistor SMD 0402")
		(property "Reference" "R8"
			(at -1.8689 7.0514 180)
			(layer "B.SilkS")
			(effects
				(font
					(size 0.7 0.7)
					(thickness 0.15)
				)
				(justify left bottom mirror)
			)
		)
		(property "Value" "R_100k_0402"
			(at -1.011843 1.772047 90)
			(layer "F.Fab")
			(effects
				(font
					(size 0.7 0.7)
					(thickness 0.15)
				)
				(justify left bottom)
			)
		)
		(property "Datasheet" "https://www.bourns.com/docs/product-datasheets/cr.pdf"
			(at 0 0 90)
			(layer "F.Fab")
			(hide yes)
			(effects
				(font
					(size 1.27 1.27)
					(thickness 0.15)
				)
			)
		)
		(property "Description" "SMD Chip Resistor, 100 kohm, ± 1%, 62.5 mW, 0402 [1005 Metric], Thick Film, General Purpose"
			(at 0 0 90)
			(layer "F.Fab")
			(hide yes)
			(effects
				(font
					(size 1.27 1.27)
					(thickness 0.15)
				)
			)
		)
		(property "Manufacturer" "Bourns"
			(at 0 0 90)
			(unlocked yes)
			(layer "F.Fab")
			(hide yes)
			(effects
				(font
					(size 1 1)
					(thickness 0.15)
				)
			)
		)
		(property "MPN" "CR0402-FX-1003GLF"
			(at 0 0 90)
			(unlocked yes)
			(layer "F.Fab")
			(hide yes)
			(effects
				(font
					(size 1 1)
					(thickness 0.15)
				)
			)
		)
		(property "Val" "100k"
			(at 0 0 90)
			(unlocked yes)
			(layer "F.Fab")
			(hide yes)
			(effects
				(font
					(size 1 1)
					(thickness 0.15)
				)
			)
		)
		(property "License" "Apache-2.0"
			(at 0 0 90)
			(unlocked yes)
			(layer "F.Fab")
			(hide yes)
			(effects
				(font
					(size 1 1)
					(thickness 0.15)
				)
			)
		)
		(property "Author" "Antmicro"
			(at 0 0 90)
			(unlocked yes)
			(layer "F.Fab")
			(hide yes)
			(effects
				(font
					(size 1 1)
					(thickness 0.15)
				)
			)
		)
		(property "Tolerance" "1%"
			(at 0 0 90)
			(unlocked yes)
			(layer "F.Fab")
			(hide yes)
			(effects
				(font
					(size 1 1)
					(thickness 0.15)
				)
			)
		)
		(sheetname "/DC-DC Converters/")
		(sheetfile "dc-dc_converters.kicad_sch")
		(attr smd)
		(fp_rect
			(start -0.925 -0.47)
			(end 0.925 0.47)
			(stroke
				(width 0.05)
				(type default)
			)
			(fill no)
			(layer "F.CrtYd")
		)
		(fp_rect
			(start -0.5 -0.25)
			(end 0.5 0.25)
			(stroke
				(width 0.15)
				(type solid)
			)
			(fill no)
			(layer "F.Fab")
		)
		(pad "1" smd roundrect
			(at -0.48 0 90)
			(size 0.59 0.64)
			(layers "F.Cu" "F.Mask" "F.Paste")
			(roundrect_rratio 0.25)
			(net 45 "Net-(U2-EN)")
			(pintype "passive")
		)
		(pad "2" smd roundrect
			(at 0.48 0 90)
			(size 0.59 0.64)
			(layers "F.Cu" "F.Mask" "F.Paste")
			(roundrect_rratio 0.25)
			(net 12 "Net-(U2-V_{CIN})")
			(pintype "passive")
		)
	)
	(footprint "antmicro-footprints:SIC47XED-T1-GE3"
		(layer "F.Cu")
		(at 95.1 84.7 -90)
		(property "Reference" "U2"
			(at -3.42 -3.579 90)
			(layer "F.SilkS")
			(effects
				(font
					(size 0.7 0.7)
					(thickness 0.15)
				)
				(justify right bottom)
			)
		)
		(property "Value" "SIC477ED-T1-GE3"
			(at 0 4.1 90)
			(layer "F.Fab")
			(effects
				(font
					(size 0.7 0.7)
					(thickness 0.15)
				)
				(justify right bottom)
			)
		)
		(property "Datasheet" "https://www.vishay.com/docs/77113/sic47x.pdf"
			(at 0 0 90)
			(layer "F.Fab")
			(hide yes)
			(effects
				(font
					(size 1.27 1.27)
					(thickness 0.15)
				)
			)
		)
		(property "Description" "DC/DC Synchronous Regulator, Adjustable, 4.5V to 55VIn, 0.8V to 50.6V/6AOut, 2MHz, PowerPAK MLP55-27"
			(at 0 0 90)
			(layer "F.Fab")
			(hide yes)
			(effects
				(font
					(size 1.27 1.27)
					(thickness 0.15)
				)
			)
		)
		(property "Manufacturer" "Vishay"
			(at 0 0 270)
			(unlocked yes)
			(layer "F.Fab")
			(hide yes)
			(effects
				(font
					(size 1 1)
					(thickness 0.15)
				)
			)
		)
		(property "MPN" "SIC477ED-T1-GE3"
			(at 0 0 270)
			(unlocked yes)
			(layer "F.Fab")
			(hide yes)
			(effects
				(font
					(size 1 1)
					(thickness 0.15)
				)
			)
		)
		(property "Author" "Antmicro"
			(at 0 0 270)
			(unlocked yes)
			(layer "F.Fab")
			(hide yes)
			(effects
				(font
					(size 1 1)
					(thickness 0.15)
				)
			)
		)
		(property "License" "Apache-2.0"
			(at 0 0 270)
			(unlocked yes)
			(layer "F.Fab")
			(hide yes)
			(effects
				(font
					(size 1 1)
					(thickness 0.15)
				)
			)
		)
		(sheetname "/DC-DC Converters/")
		(sheetfile "dc-dc_converters.kicad_sch")
		(attr smd)
		(fp_line
			(start -2.5 2.499)
			(end -2.5 2.148)
			(stroke
				(width 0.15)
				(type solid)
			)
			(layer "F.SilkS")
		)
		(fp_line
			(start -2.101 2.499)
			(end -2.5 2.499)
			(stroke
				(width 0.15)
				(type solid)
			)
			(layer "F.SilkS")
		)
		(fp_line
			(start 2.499 2.499)
			(end 2.1 2.499)
			(stroke
				(width 0.15)
				(type solid)
			)
			(layer "F.SilkS")
		)
		(fp_line
			(start 2.499 2.297)
			(end 2.499 2.499)
			(stroke
				(width 0.15)
				(type solid)
			)
			(layer "F.SilkS")
		)
		(fp_line
			(start -2.5 -2.15)
			(end -2.5 -2.5)
			(stroke
				(width 0.15)
				(type solid)
			)
			(layer "F.SilkS")
		)
		(fp_line
			(start -2.5 -2.5)
			(end -2.15 -2.5)
			(stroke
				(width 0.15)
				(type solid)
			)
			(layer "F.SilkS")
		)
		(fp_line
			(start 2.148 -2.5)
			(end 2.499 -2.5)
			(stroke
				(width 0.15)
				(type solid)
			)
			(layer "F.SilkS")
		)
		(fp_line
			(start 2.499 -2.5)
			(end 2.499 -2.15)
			(stroke
				(width 0.15)
				(type solid)
			)
			(layer "F.SilkS")
		)
		(fp_circle
			(center -2.9 -2.1)
			(end -2.849 -2.1)
			(stroke
				(width 0.15)
				(type solid)
			)
			(fill yes)
			(layer "F.SilkS")
		)
		(fp_poly
			(pts
				(xy -0.803 2.1) (xy -1.601 2.1) (xy -1.601 -0.203) (xy -0.803 -0.203)
			)
			(stroke
				(width 0.1)
				(type solid)
			)
			(fill yes)
			(layer "F.Paste")
		)
		(fp_poly
			(pts
				(xy 1.648 2.048) (xy -0.25 2.048) (xy -0.25 1.398) (xy 1.648 1.398)
			)
			(stroke
				(width 0.1)
				(type solid)
			)
			(fill yes)
			(layer "F.Paste")
		)
		(fp_poly
			(pts
				(xy 1.1 0.597) (xy -0.25 0.597) (xy -0.25 -0.25) (xy 1.1 -0.25)
			)
			(stroke
				(width 0.1)
				(type solid)
			)
			(fill yes)
			(layer "F.Paste")
		)
		(fp_poly
			(pts
				(xy -0.453 -0.75) (xy -1.601 -0.75) (xy -1.601 -1.651) (xy -0.453 -1.651)
			)
			(stroke
				(width 0.1)
				(type solid)
			)
			(fill yes)
			(layer "F.Paste")
		)
		(fp_poly
			(pts
				(xy 1.6 -0.75) (xy 0.45 -0.75) (xy 0.45 -1.651) (xy 1.6 -1.651)
			)
			(stroke
				(width 0.1)
				(type solid)
			)
			(fill yes)
			(layer "F.Paste")
		)
		(fp_line
			(start -1.9 3.2)
			(end 1.65 3.2)
			(stroke
				(width 0.05)
				(type solid)
			)
			(layer "F.CrtYd")
		)
		(fp_line
			(start 1.65 3.2)
			(end 1.65 2.75)
			(stroke
				(width 0.05)
				(type solid)
			)
			(layer "F.CrtYd")
		)
		(fp_line
			(start -2.75 2.75)
			(end -1.9 2.75)
			(stroke
				(width 0.05)
				(type solid)
			)
			(layer "F.CrtYd")
		)
		(fp_line
			(start -1.9 2.75)
			(end -1.9 3.2)
			(stroke
				(width 0.05)
				(type solid)
			)
			(layer "F.CrtYd")
		)
		(fp_line
			(start 1.65 2.75)
			(end 2.75 2.75)
			(stroke
				(width 0.05)
				(type solid)
			)
			(layer "F.CrtYd")
		)
		(fp_line
			(start 2.75 2.75)
			(end 2.75 2.3)
			(stroke
				(width 0.05)
				(type solid)
			)
			(layer "F.CrtYd")
		)
		(fp_line
			(start 2.75 2.3)
			(end 3.2 2.3)
			(stroke
				(width 0.05)
				(type solid)
			)
			(layer "F.CrtYd")
		)
		(fp_line
			(start 3.2 2.3)
			(end 3.2 -2.15)
			(stroke
				(width 0.05)
				(type solid)
			)
			(layer "F.CrtYd")
		)
		(fp_line
			(start -3.2 2.15)
			(end -2.75 2.15)
			(stroke
				(width 0.05)
				(type solid)
			)
			(layer "F.CrtYd")
		)
		(fp_line
			(start -2.75 2.15)
			(end -2.75 2.75)
			(stroke
				(width 0.05)
				(type solid)
			)
			(layer "F.CrtYd")
		)
		(fp_line
			(start -3.2 -2.1)
			(end -3.2 2.15)
			(stroke
				(width 0.05)
				(type solid)
			)
			(layer "F.CrtYd")
		)
		(fp_line
			(start -2.75 -2.1)
			(end -3.2 -2.1)
			(stroke
				(width 0.05)
				(type solid)
			)
			(layer "F.CrtYd")
		)
		(fp_line
			(start 2.75 -2.15)
			(end 2.75 -2.75)
			(stroke
				(width 0.05)
				(type solid)
			)
			(layer "F.CrtYd")
		)
		(fp_line
			(start 3.2 -2.15)
			(end 2.75 -2.15)
			(stroke
				(width 0.05)
				(type solid)
			)
			(layer "F.CrtYd")
		)
		(fp_line
			(start -2.75 -2.75)
			(end -2.75 -2.1)
			(stroke
				(width 0.05)
				(type solid)
			)
			(layer "F.CrtYd")
		)
		(fp_line
			(start -2.15 -2.75)
			(end -2.75 -2.75)
			(stroke
				(width 0.05)
				(type solid)
			)
			(layer "F.CrtYd")
		)
		(fp_line
			(start 2.15 -2.75)
			(end 2.15 -3.2)
			(stroke
				(width 0.05)
				(type solid)
			)
			(layer "F.CrtYd")
		)
		(fp_line
			(start 2.75 -2.75)
			(end 2.15 -2.75)
			(stroke
				(width 0.05)
				(type solid)
			)
			(layer "F.CrtYd")
		)
		(fp_line
			(start -2.15 -3.2)
			(end -2.15 -2.75)
			(stroke
				(width 0.05)
				(type solid)
			)
			(layer "F.CrtYd")
		)
		(fp_line
			(start 2.15 -3.2)
			(end -2.15 -3.2)
			(stroke
				(width 0.05)
				(type solid)
			)
			(layer "F.CrtYd")
		)
		(fp_line
			(start -2.5 -2.302)
			(end -2.302 -2.5)
			(stroke
				(width 0.15)
				(type solid)
			)
			(layer "F.Fab")
		)
		(fp_rect
			(start 2.499 2.499)
			(end -2.5 -2.5)
			(stroke
				(width 0.15)
				(type solid)
			)
			(fill no)
			(layer "F.Fab")
		)
		(pad "1" smd rect
			(at -2.525 -1.7 270)
			(size 0.95 0.35)
			(layers "F.Cu" "F.Mask" "F.Paste")
			(net 12 "Net-(U2-V_{CIN})")
			(pinfunction "V_{CIN}")
			(pintype "input")
		)
		(pad "2" smd rect
			(at -2.525 -1.051 270)
			(size 0.95 0.35)
			(layers "F.Cu" "F.Mask" "F.Paste")
			(net 48 "Net-(U2-P_{GOOD})")
			(pinfunction "P_{GOOD}")
			(pintype "output")
		)
		(pad "3" smd rect
			(at -2.525 -0.403 270)
			(size 0.95 0.35)
			(layers "F.Cu" "F.Mask" "F.Paste")
			(net 45 "Net-(U2-EN)")
			(pinfunction "EN")
			(pintype "input")
		)
		(pad "4" smd rect
			(at -2.525 0.247 270)
			(size 0.95 0.35)
			(layers "F.Cu" "F.Mask" "F.Paste")
			(net 17 "Net-(U2-BOOT)")
			(pinfunction "BOOT")
			(pintype "input")
		)
		(pad "5" smd rect
			(at -2.525 1.249 270)
			(size 0.95 0.35)
			(layers "F.Cu" "F.Mask" "F.Paste")
			(net 49 "Net-(R14-Pad2)")
			(pinfunction "PHASE")
			(pintype "bidirectional")
		)
		(pad "6" smd rect
			(at -2.525 1.749 270)
			(size 0.95 0.35)
			(layers "F.Cu" "F.Mask" "F.Paste")
			(net 49 "Net-(R14-Pad2)")
			(pinfunction "PHASE")
			(pintype "passive")
		)
		(pad "7" smd rect
			(at -1.52 2.523 270)
			(size 0.35 0.95)
			(layers "F.Cu" "F.Mask" "F.Paste")
			(net 12 "Net-(U2-V_{CIN})")
			(pinfunction "V_{IN}")
			(pintype "input")
		)
		(pad "7" smd rect
			(at -1.2 0.997 270)
			(size 1.1 2.7)
			(layers "F.Cu" "F.Mask")
			(net 12 "Net-(U2-V_{CIN})")
			(pinfunction "V_{IN}")
			(pintype "input")
		)
		(pad "8" smd rect
			(at -0.87 2.523 270)
			(size 0.35 0.95)
			(layers "F.Cu" "F.Mask" "F.Paste")
			(net 12 "Net-(U2-V_{CIN})")
			(pinfunction "V_{IN}")
			(pintype "passive")
		)
		(pad "9" smd rect
			(at 0.26 2.523 270)
			(size 0.35 0.95)
			(layers "F.Cu" "F.Mask" "F.Paste")
			(net 2 "GND")
			(pinfunction "PGND")
			(pintype "power_in")
		)
		(pad "9" smd rect
			(at 0.409 0.997 270)
			(size 1.52 2.7)
			(layers "F.Cu" "F.Mask")
			(net 2 "GND")
			(pinfunction "PGND")
			(pintype "power_in")
		)
		(pad "9" smd rect
			(at 0.699 1.485 270)
			(size 2.1 1.73)
			(layers "F.Cu" "F.Mask")
			(net 2 "GND")
			(pinfunction "PGND")
			(pintype "power_in")
		)
		(pad "10" smd rect
			(at 0.757 2.523 270)
			(size 0.35 0.95)
			(layers "F.Cu" "F.Mask" "F.Paste")
			(net 2 "GND")
			(pinfunction "PGND")
			(pintype "passive")
		)
		(pad "11" smd rect
			(at 1.259 2.523 270)
			(size 0.35 0.95)
			(layers "F.Cu" "F.Mask" "F.Paste")
			(net 2 "GND")
			(pinfunction "PGND")
			(pintype "passive")
		)
		(pad "12" smd rect
			(at 2.523 1.898 270)
			(size 0.95 0.35)
			(layers "F.Cu" "F.Mask" "F.Paste")
			(net 8 "Net-(L1-Pad1)")
			(pinfunction "SW")
			(pintype "bidirectional")
		)
		(pad "13" smd rect
			(at 2.523 1.398 270)
			(size 0.95 0.35)
			(layers "F.Cu" "F.Mask" "F.Paste")
			(net 8 "Net-(L1-Pad1)")
			(pinfunction "SW")
			(pintype "passive")
		)
		(pad "14" smd rect
			(at 2.2 1.398 270)
			(size 0.3 1.35)
			(layers "F.Cu" "F.Mask" "F.Paste")
			(net 8 "Net-(L1-Pad1)")
			(pinfunction "SW")
			(pintype "passive")
		)
		(pad "14" smd rect
			(at 2.523 0.9 270)
			(size 0.95 0.35)
			(layers "F.Cu" "F.Mask" "F.Paste")
			(net 8 "Net-(L1-Pad1)")
			(pinfunction "SW")
			(pintype "passive")
		)
		(pad "15" smd rect
			(at 2.523 0.247 270)
			(size 0.95 0.35)
			(layers "F.Cu" "F.Mask" "F.Paste")
			(net 59 "unconnected-(U2-GL-Pad15)")
			(pinfunction "GL")
			(pintype "input+no_connect")
		)
		(pad "16" smd rect
			(at 2.523 -0.25 270)
			(size 0.95 0.35)
			(layers "F.Cu" "F.Mask" "F.Paste")
			(net 11 "/DC-DC Converters/VDRV_12V_DCDC")
			(pinfunction "V_{DRV}")
			(pintype "passive")
		)
		(pad "17" smd rect
			(at 2.523 -0.75 270)
			(size 0.95 0.35)
			(layers "F.Cu" "F.Mask" "F.Paste")
			(net 2 "GND")
			(pinfunction "PGND")
			(pintype "passive")
		)
		(pad "18" smd rect
			(at 2.523 -1.25 270)
			(size 0.95 0.35)
			(layers "F.Cu" "F.Mask" "F.Paste")
			(net 60 "unconnected-(U2-NC-Pad18)")
			(pinfunction "NC")
			(pintype "passive+no_connect")
		)
		(pad "19" smd rect
			(at 2.523 -1.75 270)
			(size 0.95 0.35)
			(layers "F.Cu" "F.Mask" "F.Paste")
			(net 13 "/DC-DC Converters/12V_SS")
			(pinfunction "SS")
			(pintype "passive")
		)
		(pad "20" smd rect
			(at 1.749 -2.525 270)
			(size 0.35 0.95)
			(layers "F.Cu" "F.Mask" "F.Paste")
			(net 18 "Net-(U2-V_{SNS})")
			(pinfunction "V_{SNS}")
			(pintype "power_in")
		)
		(pad "21" smd rect
			(at 1.249 -2.525 270)
			(size 0.35 0.95)
			(layers "F.Cu" "F.Mask" "F.Paste")
			(net 50 "Net-(R16-Pad1)")
			(pinfunction "NC")
			(pintype "passive")
		)
		(pad "22" smd rect
			(at 0.747 -2.525 270)
			(size 0.35 0.95)
			(layers "F.Cu" "F.Mask" "F.Paste")
			(net 51 "Net-(U2-V_{FB})")
			(pinfunction "V_{FB}")
			(pintype "input")
		)
		(pad "23" smd rect
			(at 0.247 -2.525 270)
			(size 0.35 0.95)
			(layers "F.Cu" "F.Mask" "F.Paste")
			(net 2 "GND")
			(pinfunction "AGND")
			(pintype "power_in")
		)
		(pad "24" smd rect
			(at -0.25 -2.525 270)
			(size 0.35 0.95)
			(layers "F.Cu" "F.Mask" "F.Paste")
			(net 46 "/DC-DC Converters/12V_FSW")
			(pinfunction "f_{SW}")
			(pintype "passive")
		)
		(pad "25" smd rect
			(at -0.75 -2.525 270)
			(size 0.35 0.95)
			(layers "F.Cu" "F.Mask" "F.Paste")
			(net 44 "/DC-DC Converters/12V_ILIM")
			(pinfunction "I_{LIMIT}")
			(pintype "passive")
		)
		(pad "26" smd rect
			(at -1.25 -2.525 270)
			(size 0.35 0.95)
			(layers "F.Cu" "F.Mask" "F.Paste")
			(net 10 "/DC-DC Converters/VDD_12V_DCDC")
			(pinfunction "V_{DD}")
			(pintype "power_out")
		)
		(pad "27" smd rect
			(at -1.75 -2.525 270)
			(size 0.35 0.95)
			(layers "F.Cu" "F.Mask" "F.Paste")
			(net 43 "/DC-DC Converters/12V_MODE")
			(pinfunction "MODE")
			(pintype "bidirectional")
		)
		(pad "28" smd rect
			(at 0 -1.2 270)
			(size 3.4 1.1)
			(layers "F.Cu" "F.Mask")
			(net 2 "GND")
			(pinfunction "AGND")
			(pintype "passive")
		)
	)
	(footprint "antmicro-footprints:Conn_JST_SH_1x4_SM04B-SRSS-TB-LF-SN"
		(layer "F.Cu")
		(at 87.9 63.1 180)
		(property "Reference" "J2"
			(at 1.05 3.15 180)
			(layer "F.SilkS")
			(effects
				(font
					(size 0.7 0.7)
					(thickness 0.15)
				)
				(justify right bottom)
			)
		)
		(property "Value" "JST_SH_1x4_SM04B-SRSS-TB-LF-SN"
			(at 0 3.9 0)
			(layer "F.Fab")
			(effects
				(font
					(size 0.7 0.7)
					(thickness 0.15)
				)
				(justify right bottom)
			)
		)
		(property "Datasheet" "https://www.jst-mfg.com/product/pdf/eng/eSH.pdf"
			(at 0 0 180)
			(layer "F.Fab")
			(hide yes)
			(effects
				(font
					(size 1.27 1.27)
					(thickness 0.15)
				)
			)
		)
		(property "Description" "Pin Header, Right Angle, Wire-to-Board, 1 mm, 1 Rows, 4 Contacts, Surface Mount Right Angle, SH"
			(at 0 0 180)
			(layer "F.Fab")
			(hide yes)
			(effects
				(font
					(size 1.27 1.27)
					(thickness 0.15)
				)
			)
		)
		(property "MPN" "SM04B-SRSS-TB(LF)(SN)"
			(at 0 0 180)
			(unlocked yes)
			(layer "F.Fab")
			(hide yes)
			(effects
				(font
					(size 1 1)
					(thickness 0.15)
				)
			)
		)
		(property "Manufacturer" "JST Automotive Connectors"
			(at 0 0 180)
			(unlocked yes)
			(layer "F.Fab")
			(hide yes)
			(effects
				(font
					(size 1 1)
					(thickness 0.15)
				)
			)
		)
		(property "Author" "Antmicro"
			(at 0 0 180)
			(unlocked yes)
			(layer "F.Fab")
			(hide yes)
			(effects
				(font
					(size 1 1)
					(thickness 0.15)
				)
			)
		)
		(property "License" "Apache-2.0"
			(at 0 0 180)
			(unlocked yes)
			(layer "F.Fab")
			(hide yes)
			(effects
				(font
					(size 1 1)
					(thickness 0.15)
				)
			)
		)
		(sheetname "/USB PD/")
		(sheetfile "usb_pd.kicad_sch")
		(attr smd)
		(fp_line
			(start 3.2 -2)
			(end 3.2 0.6)
			(stroke
				(width 0.15)
				(type solid)
			)
			(layer "F.SilkS")
		)
		(fp_line
			(start 2 -2)
			(end 3.2 -2)
			(stroke
				(width 0.15)
				(type solid)
			)
			(layer "F.SilkS")
		)
		(fp_line
			(start -2 2.6)
			(end 2 2.6)
			(stroke
				(width 0.15)
				(type solid)
			)
			(layer "F.SilkS")
		)
		(fp_line
			(start -2 -2)
			(end -3.2 -2)
			(stroke
				(width 0.15)
				(type solid)
			)
			(layer "F.SilkS")
		)
		(fp_line
			(start -3.2 -2)
			(end -3.2 0.6)
			(stroke
				(width 0.15)
				(type solid)
			)
			(layer "F.SilkS")
		)
		(fp_circle
			(center -2.1 -2.5)
			(end -2.05 -2.5)
			(stroke
				(width 0.15)
				(type solid)
			)
			(fill yes)
			(layer "F.SilkS")
		)
		(fp_rect
			(start -3.65 -3.14)
			(end 3.65 2.9)
			(stroke
				(width 0.05)
				(type solid)
			)
			(fill no)
			(layer "F.CrtYd")
		)
		(fp_rect
			(start -3 -2.475)
			(end 3 2.475)
			(stroke
				(width 0.15)
				(type solid)
			)
			(fill no)
			(layer "F.Fab")
		)
		(pad "1" smd roundrect
			(at -1.5 -2.12)
			(size 0.6 1.55)
			(layers "F.Cu" "F.Mask" "F.Paste")
			(roundrect_rratio 0.25)
			(net 2 "GND")
			(pintype "passive")
		)
		(pad "2" smd roundrect
			(at -0.5 -2.12)
			(size 0.6 1.55)
			(layers "F.Cu" "F.Mask" "F.Paste")
			(roundrect_rratio 0.25)
			(net 61 "/USB PD/QWIIC_VCC")
			(pintype "passive")
		)
		(pad "3" smd roundrect
			(at 0.5 -2.12)
			(size 0.6 1.55)
			(layers "F.Cu" "F.Mask" "F.Paste")
			(roundrect_rratio 0.25)
			(net 37 "/USB PD/SDA")
			(pintype "passive")
		)
		(pad "4" smd roundrect
			(at 1.5 -2.12)
			(size 0.6 1.55)
			(layers "F.Cu" "F.Mask" "F.Paste")
			(roundrect_rratio 0.25)
			(net 38 "/USB PD/SCL")
			(pintype "passive")
		)
		(pad "MP" smd roundrect
			(at -2.8 1.755 180)
			(size 1.2 1.8)
			(layers "F.Cu" "F.Mask" "F.Paste")
			(roundrect_rratio 0.25)
			(net 2 "GND")
			(pintype "passive")
		)
		(pad "MP" smd roundrect
			(at 2.8 1.755 180)
			(size 1.2 1.8)
			(layers "F.Cu" "F.Mask" "F.Paste")
			(roundrect_rratio 0.25)
			(net 2 "GND")
			(pintype "passive")
		)
	)
	(footprint "antmicro-footprints:C_0402_1005Metric"
		(layer "F.Cu")
		(at 89 67.2 180)
		(descr "Capacitor SMD 0402")
		(tags "capacitor SMD 0402")
		(property "Reference" "C28"
			(at -1 -0.8 0)
			(layer "F.SilkS")
			(effects
				(font
					(size 0.7 0.7)
					(thickness 0.15)
				)
				(justify left bottom)
			)
		)
		(property "Value" "C_100n_50V_X8L_0402"
			(at -1.022927 2.155213 0)
			(layer "F.Fab")
			(effects
				(font
					(size 0.7 0.7)
					(thickness 0.15)
				)
				(justify right bottom)
			)
		)
		(property "Datasheet" "https://www.murata.com/products/productdetail?partno=GCM155L8EH104KE07%23"
			(at 0 0 180)
			(layer "F.Fab")
			(hide yes)
			(effects
				(font
					(size 1.27 1.27)
					(thickness 0.15)
				)
			)
		)
		(property "Description" "SMD Multilayer Ceramic Capacitor, 100nF, 50V, 0402, ±10%, X8L"
			(at 0 0 180)
			(layer "F.Fab")
			(hide yes)
			(effects
				(font
					(size 1.27 1.27)
					(thickness 0.15)
				)
			)
		)
		(property "MPN" "GCM155L8EH104KE07D"
			(at 0 0 180)
			(unlocked yes)
			(layer "F.Fab")
			(hide yes)
			(effects
				(font
					(size 1 1)
					(thickness 0.15)
				)
			)
		)
		(property "Val" "100n"
			(at 0 0 180)
			(unlocked yes)
			(layer "F.Fab")
			(hide yes)
			(effects
				(font
					(size 1 1)
					(thickness 0.15)
				)
			)
		)
		(property "Voltage" "50V"
			(at 0 0 180)
			(unlocked yes)
			(layer "F.Fab")
			(hide yes)
			(effects
				(font
					(size 1 1)
					(thickness 0.15)
				)
			)
		)
		(property "Dielectric" "X8L"
			(at 0 0 180)
			(unlocked yes)
			(layer "F.Fab")
			(hide yes)
			(effects
				(font
					(size 1 1)
					(thickness 0.15)
				)
			)
		)
		(property "Manufacturer" "Murata"
			(at 0 0 180)
			(unlocked yes)
			(layer "F.Fab")
			(hide yes)
			(effects
				(font
					(size 1 1)
					(thickness 0.15)
				)
			)
		)
		(property "License" "Apache-2.0"
			(at 0 0 180)
			(unlocked yes)
			(layer "F.Fab")
			(hide yes)
			(effects
				(font
					(size 1 1)
					(thickness 0.15)
				)
			)
		)
		(property "Author" "Antmicro"
			(at 0 0 180)
			(unlocked yes)
			(layer "F.Fab")
			(hide yes)
			(effects
				(font
					(size 1 1)
					(thickness 0.15)
				)
			)
		)
		(sheetname "/USB PD/")
		(sheetfile "usb_pd.kicad_sch")
		(attr smd)
		(fp_rect
			(start -0.925 -0.47)
			(end 0.925 0.47)
			(stroke
				(width 0.05)
				(type default)
			)
			(fill no)
			(layer "F.CrtYd")
		)
		(fp_line
			(start 0.504 0.248)
			(end -0.494 0.248)
			(stroke
				(width 0.15)
				(type solid)
			)
			(layer "F.Fab")
		)
		(fp_line
			(start 0.504 -0.25)
			(end 0.504 0.248)
			(stroke
				(width 0.15)
				(type solid)
			)
			(layer "F.Fab")
		)
		(fp_line
			(start -0.494 0.248)
			(end -0.494 -0.25)
			(stroke
				(width 0.15)
				(type solid)
			)
			(layer "F.Fab")
		)
		(fp_line
			(start -0.494 -0.25)
			(end 0.504 -0.25)
			(stroke
				(width 0.15)
				(type solid)
			)
			(layer "F.Fab")
		)
		(pad "1" smd roundrect
			(at -0.48 0 180)
			(size 0.59 0.64)
			(layers "F.Cu" "F.Mask" "F.Paste")
			(roundrect_rratio 0.25)
			(net 2 "GND")
			(pintype "passive")
		)
		(pad "2" smd roundrect
			(at 0.48 0 180)
			(size 0.59 0.64)
			(layers "F.Cu" "F.Mask" "F.Paste")
			(roundrect_rratio 0.25)
			(net 61 "/USB PD/QWIIC_VCC")
			(pintype "passive")
		)
	)
	(footprint "antmicro-footprints:C_0402_1005Metric"
		(layer "F.Cu")
		(at 94.8 80.3 -90)
		(descr "Capacitor SMD 0402")
		(tags "capacitor SMD 0402")
		(property "Reference" "C10"
			(at 0.8529 -8.0514 180)
			(layer "B.SilkS")
			(effects
				(font
					(size 0.7 0.7)
					(thickness 0.15)
				)
				(justify left bottom mirror)
			)
		)
		(property "Value" "C_100n_50V_X8L_0402"
			(at -1.022927 2.155213 90)
			(layer "F.Fab")
			(effects
				(font
					(size 0.7 0.7)
					(thickness 0.15)
				)
				(justify right bottom)
			)
		)
		(property "Datasheet" "https://www.murata.com/products/productdetail?partno=GCM155L8EH104KE07%23"
			(at 0 0 270)
			(layer "F.Fab")
			(hide yes)
			(effects
				(font
					(size 1.27 1.27)
					(thickness 0.15)
				)
			)
		)
		(property "Description" "SMD Multilayer Ceramic Capacitor, 100nF, 50V, 0402, ±10%, X8L"
			(at 0 0 270)
			(layer "F.Fab")
			(hide yes)
			(effects
				(font
					(size 1.27 1.27)
					(thickness 0.15)
				)
			)
		)
		(property "MPN" "GCM155L8EH104KE07D"
			(at 0 0 270)
			(unlocked yes)
			(layer "F.Fab")
			(hide yes)
			(effects
				(font
					(size 1 1)
					(thickness 0.15)
				)
			)
		)
		(property "Val" "100n"
			(at 0 0 270)
			(unlocked yes)
			(layer "F.Fab")
			(hide yes)
			(effects
				(font
					(size 1 1)
					(thickness 0.15)
				)
			)
		)
		(property "Voltage" "50V"
			(at 0 0 270)
			(unlocked yes)
			(layer "F.Fab")
			(hide yes)
			(effects
				(font
					(size 1 1)
					(thickness 0.15)
				)
			)
		)
		(property "Dielectric" "X8L"
			(at 0 0 270)
			(unlocked yes)
			(layer "F.Fab")
			(hide yes)
			(effects
				(font
					(size 1 1)
					(thickness 0.15)
				)
			)
		)
		(property "Manufacturer" "Murata"
			(at 0 0 270)
			(unlocked yes)
			(layer "F.Fab")
			(hide yes)
			(effects
				(font
					(size 1 1)
					(thickness 0.15)
				)
			)
		)
		(property "License" "Apache-2.0"
			(at 0 0 270)
			(unlocked yes)
			(layer "F.Fab")
			(hide yes)
			(effects
				(font
					(size 1 1)
					(thickness 0.15)
				)
			)
		)
		(property "Author" "Antmicro"
			(at 0 0 270)
			(unlocked yes)
			(layer "F.Fab")
			(hide yes)
			(effects
				(font
					(size 1 1)
					(thickness 0.15)
				)
			)
		)
		(sheetname "/DC-DC Converters/")
		(sheetfile "dc-dc_converters.kicad_sch")
		(attr smd)
		(fp_rect
			(start -0.925 -0.47)
			(end 0.925 0.47)
			(stroke
				(width 0.05)
				(type default)
			)
			(fill no)
			(layer "F.CrtYd")
		)
		(fp_line
			(start -0.494 0.248)
			(end -0.494 -0.25)
			(stroke
				(width 0.15)
				(type solid)
			)
			(layer "F.Fab")
		)
		(fp_line
			(start 0.504 0.248)
			(end -0.494 0.248)
			(stroke
				(width 0.15)
				(type solid)
			)
			(layer "F.Fab")
		)
		(fp_line
			(start -0.494 -0.25)
			(end 0.504 -0.25)
			(stroke
				(width 0.15)
				(type solid)
			)
			(layer "F.Fab")
		)
		(fp_line
			(start 0.504 -0.25)
			(end 0.504 0.248)
			(stroke
				(width 0.15)
				(type solid)
			)
			(layer "F.Fab")
		)
		(pad "1" smd roundrect
			(at -0.48 0 270)
			(size 0.59 0.64)
			(layers "F.Cu" "F.Mask" "F.Paste")
			(roundrect_rratio 0.25)
			(net 16 "Net-(C10-Pad1)")
			(pintype "passive")
		)
		(pad "2" smd roundrect
			(at 0.48 0 270)
			(size 0.59 0.64)
			(layers "F.Cu" "F.Mask" "F.Paste")
			(roundrect_rratio 0.25)
			(net 17 "Net-(U2-BOOT)")
			(pintype "passive")
		)
	)
	(footprint "antmicro-footprints:TP_SMD_0.75mm"
		(layer "F.Cu")
		(at 86.576 76.45)
		(property "Reference" "TP11"
			(at -9.057 3.202 0)
			(layer "F.SilkS")
			(hide yes)
			(effects
				(font
					(size 0.7 0.7)
					(thickness 0.15)
				)
				(justify left bottom)
			)
		)
		(property "Value" "TP_0.75mm_SMD"
			(at 0 1.2 0)
			(layer "F.Fab")
			(effects
				(font
					(size 0.7 0.7)
					(thickness 0.15)
				)
				(justify left bottom)
			)
		)
		(property "Description" "SMT test point"
			(at 0 0 0)
			(layer "F.Fab")
			(hide yes)
			(effects
				(font
					(size 1.27 1.27)
					(thickness 0.15)
				)
			)
		)
		(property "MPN" ""
			(at 0 0 0)
			(unlocked yes)
			(layer "F.Fab")
			(hide yes)
			(effects
				(font
					(size 1 1)
					(thickness 0.15)
				)
			)
		)
		(property "Manufacturer" ""
			(at 0 0 0)
			(unlocked yes)
			(layer "F.Fab")
			(hide yes)
			(effects
				(font
					(size 1 1)
					(thickness 0.15)
				)
			)
		)
		(property "Author" "Antmicro"
			(at 0 0 0)
			(unlocked yes)
			(layer "F.Fab")
			(hide yes)
			(effects
				(font
					(size 1 1)
					(thickness 0.15)
				)
			)
		)
		(property "License" "Apache-2.0"
			(at 0 0 0)
			(unlocked yes)
			(layer "F.Fab")
			(hide yes)
			(effects
				(font
					(size 1 1)
					(thickness 0.15)
				)
			)
		)
		(sheetname "/USB PD/")
		(sheetfile "usb_pd.kicad_sch")
		(attr exclude_from_bom)
		(fp_circle
			(center 0 0)
			(end 0.475 0)
			(stroke
				(width 0.05)
				(type default)
			)
			(fill no)
			(layer "F.CrtYd")
		)
		(pad "1" smd circle
			(at 0 0)
			(size 0.75 0.75)
			(layers "F.Cu" "F.Mask")
			(net 56 "Net-(U1-A_B_SIDE)")
			(pinfunction "1")
			(pintype "passive")
		)
	)
	(footprint "antmicro-footprints:R_0402_1005Metric"
		(layer "F.Cu")
		(at 100.25 86.6)
		(descr "Resistor SMD 0402")
		(tags "resistor SMD 0402")
		(property "Reference" "R16"
			(at 0.842 0.522 0)
			(layer "F.SilkS")
			(effects
				(font
					(size 0.7 0.7)
					(thickness 0.15)
				)
				(justify left bottom)
			)
		)
		(property "Value" "R_316k_0402"
			(at -1.011843 1.772047 0)
			(layer "F.Fab")
			(effects
				(font
					(size 0.7 0.7)
					(thickness 0.15)
				)
				(justify left bottom)
			)
		)
		(property "Datasheet" "https://www.bourns.com/docs/product-datasheets/cr.pdf"
			(at 0 0 0)
			(layer "F.Fab")
			(hide yes)
			(effects
				(font
					(size 1.27 1.27)
					(thickness 0.15)
				)
			)
		)
		(property "Description" "SMD Chip Resistor"
			(at 0 0 0)
			(layer "F.Fab")
			(hide yes)
			(effects
				(font
					(size 1.27 1.27)
					(thickness 0.15)
				)
			)
		)
		(property "Manufacturer" "Bourns"
			(at 0 0 0)
			(unlocked yes)
			(layer "F.Fab")
			(hide yes)
			(effects
				(font
					(size 1 1)
					(thickness 0.15)
				)
			)
		)
		(property "MPN" "CR0402-FX-3163GLF"
			(at 0 0 0)
			(unlocked yes)
			(layer "F.Fab")
			(hide yes)
			(effects
				(font
					(size 1 1)
					(thickness 0.15)
				)
			)
		)
		(property "Val" "316k"
			(at 0 0 0)
			(unlocked yes)
			(layer "F.Fab")
			(hide yes)
			(effects
				(font
					(size 1 1)
					(thickness 0.15)
				)
			)
		)
		(property "License" "Apache-2.0"
			(at 0 0 0)
			(unlocked yes)
			(layer "F.Fab")
			(hide yes)
			(effects
				(font
					(size 1 1)
					(thickness 0.15)
				)
			)
		)
		(property "Author" "Antmicro"
			(at 0 0 0)
			(unlocked yes)
			(layer "F.Fab")
			(hide yes)
			(effects
				(font
					(size 1 1)
					(thickness 0.15)
				)
			)
		)
		(property "Tolerance" "1%"
			(at 0 0 0)
			(unlocked yes)
			(layer "F.Fab")
			(hide yes)
			(effects
				(font
					(size 1 1)
					(thickness 0.15)
				)
			)
		)
		(sheetname "/DC-DC Converters/")
		(sheetfile "dc-dc_converters.kicad_sch")
		(attr smd exclude_from_pos_files exclude_from_bom dnp)
		(fp_rect
			(start -0.925 -0.47)
			(end 0.925 0.47)
			(stroke
				(width 0.05)
				(type default)
			)
			(fill no)
			(layer "F.CrtYd")
		)
		(fp_rect
			(start -0.5 -0.25)
			(end 0.5 0.25)
			(stroke
				(width 0.15)
				(type solid)
			)
			(fill no)
			(layer "F.Fab")
		)
		(pad "1" smd roundrect
			(at -0.48 0)
			(size 0.59 0.64)
			(layers "F.Cu" "F.Mask" "F.Paste")
			(roundrect_rratio 0.25)
			(net 50 "Net-(R16-Pad1)")
			(pintype "passive")
		)
		(pad "2" smd roundrect
			(at 0.48 0)
			(size 0.59 0.64)
			(layers "F.Cu" "F.Mask" "F.Paste")
			(roundrect_rratio 0.25)
			(net 4 "Net-(C13-Pad1)")
			(pintype "passive")
		)
	)
	(footprint "antmicro-footprints:TP_SMD_0.75mm"
		(layer "F.Cu")
		(at 90.626 89.875)
		(property "Reference" "TP5"
			(at -9.996 -1.3292 0)
			(layer "F.SilkS")
			(hide yes)
			(effects
				(font
					(size 0.7 0.7)
					(thickness 0.15)
				)
				(justify left bottom)
			)
		)
		(property "Value" "TP_0.75mm_SMD"
			(at 0 1.2 0)
			(layer "F.Fab")
			(effects
				(font
					(size 0.7 0.7)
					(thickness 0.15)
				)
				(justify left bottom)
			)
		)
		(property "Description" "SMT test point"
			(at 0 0 0)
			(layer "F.Fab")
			(hide yes)
			(effects
				(font
					(size 1.27 1.27)
					(thickness 0.15)
				)
			)
		)
		(property "MPN" ""
			(at 0 0 0)
			(unlocked yes)
			(layer "F.Fab")
			(hide yes)
			(effects
				(font
					(size 1 1)
					(thickness 0.15)
				)
			)
		)
		(property "Manufacturer" ""
			(at 0 0 0)
			(unlocked yes)
			(layer "F.Fab")
			(hide yes)
			(effects
				(font
					(size 1 1)
					(thickness 0.15)
				)
			)
		)
		(property "Author" "Antmicro"
			(at 0 0 0)
			(unlocked yes)
			(layer "F.Fab")
			(hide yes)
			(effects
				(font
					(size 1 1)
					(thickness 0.15)
				)
			)
		)
		(property "License" "Apache-2.0"
			(at 0 0 0)
			(unlocked yes)
			(layer "F.Fab")
			(hide yes)
			(effects
				(font
					(size 1 1)
					(thickness 0.15)
				)
			)
		)
		(sheetname "/DC-DC Converters/")
		(sheetfile "dc-dc_converters.kicad_sch")
		(attr exclude_from_bom)
		(fp_circle
			(center 0 0)
			(end 0.475 0)
			(stroke
				(width 0.05)
				(type default)
			)
			(fill no)
			(layer "F.CrtYd")
		)
		(pad "1" smd circle
			(at 0 0)
			(size 0.75 0.75)
			(layers "F.Cu" "F.Mask")
			(net 25 "+5V")
			(pinfunction "1")
			(pintype "passive")
		)
	)
	(footprint "antmicro-footprints:R_0402_1005Metric"
		(layer "F.Cu")
		(at 86.026 77.575)
		(descr "Resistor SMD 0402")
		(tags "resistor SMD 0402")
		(property "Reference" "R21"
			(at -1.057 2.202 180)
			(layer "F.SilkS")
			(effects
				(font
					(size 0.7 0.7)
					(thickness 0.15)
				)
				(justify left bottom)
			)
		)
		(property "Value" "R_100k_0402"
			(at -1.011843 1.772047 0)
			(layer "F.Fab")
			(effects
				(font
					(size 0.7 0.7)
					(thickness 0.15)
				)
				(justify left bottom)
			)
		)
		(property "Datasheet" "https://www.bourns.com/docs/product-datasheets/cr.pdf"
			(at 0 0 0)
			(layer "F.Fab")
			(hide yes)
			(effects
				(font
					(size 1.27 1.27)
					(thickness 0.15)
				)
			)
		)
		(property "Description" "SMD Chip Resistor, 100 kohm, ± 1%, 62.5 mW, 0402 [1005 Metric], Thick Film, General Purpose"
			(at 0 0 0)
			(layer "F.Fab")
			(hide yes)
			(effects
				(font
					(size 1.27 1.27)
					(thickness 0.15)
				)
			)
		)
		(property "MPN" "CR0402-FX-1003GLF"
			(at 0 0 0)
			(unlocked yes)
			(layer "F.Fab")
			(hide yes)
			(effects
				(font
					(size 1 1)
					(thickness 0.15)
				)
			)
		)
		(property "Manufacturer" "Bourns"
			(at 0 0 0)
			(unlocked yes)
			(layer "F.Fab")
			(hide yes)
			(effects
				(font
					(size 1 1)
					(thickness 0.15)
				)
			)
		)
		(property "License" "Apache-2.0"
			(at 0 0 0)
			(unlocked yes)
			(layer "F.Fab")
			(hide yes)
			(effects
				(font
					(size 1 1)
					(thickness 0.15)
				)
			)
		)
		(property "Author" "Antmicro"
			(at 0 0 0)
			(unlocked yes)
			(layer "F.Fab")
			(hide yes)
			(effects
				(font
					(size 1 1)
					(thickness 0.15)
				)
			)
		)
		(property "Val" "100k"
			(at 0 0 0)
			(unlocked yes)
			(layer "F.Fab")
			(hide yes)
			(effects
				(font
					(size 1 1)
					(thickness 0.15)
				)
			)
		)
		(property "Tolerance" "1%"
			(at 0 0 0)
			(unlocked yes)
			(layer "F.Fab")
			(hide yes)
			(effects
				(font
					(size 1 1)
					(thickness 0.15)
				)
			)
		)
		(sheetname "/USB PD/")
		(sheetfile "usb_pd.kicad_sch")
		(attr smd)
		(fp_rect
			(start -0.925 -0.47)
			(end 0.925 0.47)
			(stroke
				(width 0.05)
				(type default)
			)
			(fill no)
			(layer "F.CrtYd")
		)
		(fp_rect
			(start -0.5 -0.25)
			(end 0.5 0.25)
			(stroke
				(width 0.15)
				(type solid)
			)
			(fill no)
			(layer "F.Fab")
		)
		(pad "1" smd roundrect
			(at -0.48 0)
			(size 0.59 0.64)
			(layers "F.Cu" "F.Mask" "F.Paste")
			(roundrect_rratio 0.25)
			(net 7 "Net-(Q1-G)")
			(pintype "passive")
		)
		(pad "2" smd roundrect
			(at 0.48 0)
			(size 0.59 0.64)
			(layers "F.Cu" "F.Mask" "F.Paste")
			(roundrect_rratio 0.25)
			(net 6 "VBUS")
			(pintype "passive")
		)
	)
	(footprint "antmicro-footprints:R_0402_1005Metric"
		(layer "F.Cu")
		(at 84.35 69.75 90)
		(descr "Resistor SMD 0402")
		(tags "resistor SMD 0402")
		(property "Reference" "R4"
			(at 1.17 0.486 90)
			(layer "F.SilkS")
			(effects
				(font
					(size 0.7 0.7)
					(thickness 0.15)
				)
				(justify left bottom)
			)
		)
		(property "Value" "R_10k_0402"
			(at -1.011843 1.772047 90)
			(layer "F.Fab")
			(effects
				(font
					(size 0.7 0.7)
					(thickness 0.15)
				)
				(justify left bottom)
			)
		)
		(property "Datasheet" "https://www.bourns.com/docs/product-datasheets/cr.pdf"
			(at 0 0 90)
			(layer "F.Fab")
			(hide yes)
			(effects
				(font
					(size 1.27 1.27)
					(thickness 0.15)
				)
			)
		)
		(property "Description" "SMD Chip Resistor, 10 kohm, ± 1%, 62.5 mW, 0402 [1005 Metric], Thick Film, General Purpose"
			(at 0 0 90)
			(layer "F.Fab")
			(hide yes)
			(effects
				(font
					(size 1.27 1.27)
					(thickness 0.15)
				)
			)
		)
		(property "MPN" "CR0402-FX-1002GLF"
			(at 0 0 90)
			(unlocked yes)
			(layer "F.Fab")
			(hide yes)
			(effects
				(font
					(size 1 1)
					(thickness 0.15)
				)
			)
		)
		(property "Manufacturer" "Bourns"
			(at 0 0 90)
			(unlocked yes)
			(layer "F.Fab")
			(hide yes)
			(effects
				(font
					(size 1 1)
					(thickness 0.15)
				)
			)
		)
		(property "License" "Apache-2.0"
			(at 0 0 90)
			(unlocked yes)
			(layer "F.Fab")
			(hide yes)
			(effects
				(font
					(size 1 1)
					(thickness 0.15)
				)
			)
		)
		(property "Author" "Antmicro"
			(at 0 0 90)
			(unlocked yes)
			(layer "F.Fab")
			(hide yes)
			(effects
				(font
					(size 1 1)
					(thickness 0.15)
				)
			)
		)
		(property "Val" "10k"
			(at 0 0 90)
			(unlocked yes)
			(layer "F.Fab")
			(hide yes)
			(effects
				(font
					(size 1 1)
					(thickness 0.15)
				)
			)
		)
		(property "Tolerance" "1%"
			(at 0 0 90)
			(unlocked yes)
			(layer "F.Fab")
			(hide yes)
			(effects
				(font
					(size 1 1)
					(thickness 0.15)
				)
			)
		)
		(sheetname "/USB PD/")
		(sheetfile "usb_pd.kicad_sch")
		(attr smd)
		(fp_rect
			(start -0.925 -0.47)
			(end 0.925 0.47)
			(stroke
				(width 0.05)
				(type default)
			)
			(fill no)
			(layer "F.CrtYd")
		)
		(fp_rect
			(start -0.5 -0.25)
			(end 0.5 0.25)
			(stroke
				(width 0.15)
				(type solid)
			)
			(fill no)
			(layer "F.Fab")
		)
		(pad "1" smd roundrect
			(at -0.48 0 90)
			(size 0.59 0.64)
			(layers "F.Cu" "F.Mask" "F.Paste")
			(roundrect_rratio 0.25)
			(net 42 "Net-(U1-RESET)")
			(pintype "passive")
		)
		(pad "2" smd roundrect
			(at 0.48 0 90)
			(size 0.59 0.64)
			(layers "F.Cu" "F.Mask" "F.Paste")
			(roundrect_rratio 0.25)
			(net 2 "GND")
			(pintype "passive")
		)
	)
	(footprint "antmicro-footprints:C_0402_1005Metric"
		(layer "F.Cu")
		(at 100 85.577)
		(descr "Capacitor SMD 0402")
		(tags "capacitor SMD 0402")
		(property "Reference" "C15"
			(at 1.092 0.529 0)
			(layer "F.SilkS")
			(effects
				(font
					(size 0.7 0.7)
					(thickness 0.15)
				)
				(justify left bottom)
			)
		)
		(property "Value" "C_100n_50V_X8L_0402"
			(at -1.022927 2.155213 0)
			(layer "F.Fab")
			(effects
				(font
					(size 0.7 0.7)
					(thickness 0.15)
				)
				(justify left bottom)
			)
		)
		(property "Datasheet" "https://www.murata.com/products/productdetail?partno=GCM155L8EH104KE07%23"
			(at 0 0 0)
			(layer "F.Fab")
			(hide yes)
			(effects
				(font
					(size 1.27 1.27)
					(thickness 0.15)
				)
			)
		)
		(property "Description" "SMD Multilayer Ceramic Capacitor, 100nF, 50V, 0402, ±10%, X8L"
			(at 0 0 0)
			(layer "F.Fab")
			(hide yes)
			(effects
				(font
					(size 1.27 1.27)
					(thickness 0.15)
				)
			)
		)
		(property "MPN" "GCM155L8EH104KE07D"
			(at 0 0 0)
			(unlocked yes)
			(layer "F.Fab")
			(hide yes)
			(effects
				(font
					(size 1 1)
					(thickness 0.15)
				)
			)
		)
		(property "Val" "100n"
			(at 0 0 0)
			(unlocked yes)
			(layer "F.Fab")
			(hide yes)
			(effects
				(font
					(size 1 1)
					(thickness 0.15)
				)
			)
		)
		(property "Voltage" "50V"
			(at 0 0 0)
			(unlocked yes)
			(layer "F.Fab")
			(hide yes)
			(effects
				(font
					(size 1 1)
					(thickness 0.15)
				)
			)
		)
		(property "Dielectric" "X8L"
			(at 0 0 0)
			(unlocked yes)
			(layer "F.Fab")
			(hide yes)
			(effects
				(font
					(size 1 1)
					(thickness 0.15)
				)
			)
		)
		(property "Manufacturer" "Murata"
			(at 0 0 0)
			(unlocked yes)
			(layer "F.Fab")
			(hide yes)
			(effects
				(font
					(size 1 1)
					(thickness 0.15)
				)
			)
		)
		(property "License" "Apache-2.0"
			(at 0 0 0)
			(unlocked yes)
			(layer "F.Fab")
			(hide yes)
			(effects
				(font
					(size 1 1)
					(thickness 0.15)
				)
			)
		)
		(property "Author" "Antmicro"
			(at 0 0 0)
			(unlocked yes)
			(layer "F.Fab")
			(hide yes)
			(effects
				(font
					(size 1 1)
					(thickness 0.15)
				)
			)
		)
		(sheetname "/DC-DC Converters/")
		(sheetfile "dc-dc_converters.kicad_sch")
		(attr smd)
		(fp_rect
			(start -0.925 -0.47)
			(end 0.925 0.47)
			(stroke
				(width 0.05)
				(type default)
			)
			(fill no)
			(layer "F.CrtYd")
		)
		(fp_line
			(start -0.494 -0.25)
			(end 0.504 -0.25)
			(stroke
				(width 0.15)
				(type solid)
			)
			(layer "F.Fab")
		)
		(fp_line
			(start -0.494 0.248)
			(end -0.494 -0.25)
			(stroke
				(width 0.15)
				(type solid)
			)
			(layer "F.Fab")
		)
		(fp_line
			(start 0.504 -0.25)
			(end 0.504 0.248)
			(stroke
				(width 0.15)
				(type solid)
			)
			(layer "F.Fab")
		)
		(fp_line
			(start 0.504 0.248)
			(end -0.494 0.248)
			(stroke
				(width 0.15)
				(type solid)
			)
			(layer "F.Fab")
		)
		(pad "1" smd roundrect
			(at -0.48 0)
			(size 0.59 0.64)
			(layers "F.Cu" "F.Mask" "F.Paste")
			(roundrect_rratio 0.25)
			(net 2 "GND")
			(pintype "passive")
		)
		(pad "2" smd roundrect
			(at 0.48 0)
			(size 0.59 0.64)
			(layers "F.Cu" "F.Mask" "F.Paste")
			(roundrect_rratio 0.25)
			(net 5 "+12V")
			(pintype "passive")
		)
	)
	(footprint "antmicro-footprints:Conn_Molex_Nano-Fit_1x2_1053131102"
		(layer "F.Cu")
		(at 86.93 101.9275)
		(property "Reference" "J4"
			(at 2.07 0.5725 90)
			(layer "F.SilkS")
			(effects
				(font
					(size 0.7 0.7)
					(thickness 0.15)
				)
				(justify left bottom)
			)
		)
		(property "Value" "Molex_Nano-Fit_1x2_1053131202"
			(at 0 13.1 0)
			(layer "F.Fab")
			(effects
				(font
					(size 0.7 0.7)
					(thickness 0.15)
				)
				(justify left bottom)
			)
		)
		(property "Datasheet" "https://tools.molex.com/pdm_docs/ps/PS-105300-100-001.pdf"
			(at 0 0 0)
			(layer "F.Fab")
			(hide yes)
			(effects
				(font
					(size 1.27 1.27)
					(thickness 0.15)
				)
			)
		)
		(property "Description" "Rectangular connector, header, Through Hole, Right Angle 2 position"
			(at 0 0 0)
			(layer "F.Fab")
			(hide yes)
			(effects
				(font
					(size 1.27 1.27)
					(thickness 0.15)
				)
			)
		)
		(property "Manufacturer" "Molex"
			(at 0 0 0)
			(unlocked yes)
			(layer "F.Fab")
			(hide yes)
			(effects
				(font
					(size 1 1)
					(thickness 0.15)
				)
			)
		)
		(property "MPN" "1053131202"
			(at 0 0 0)
			(unlocked yes)
			(layer "F.Fab")
			(hide yes)
			(effects
				(font
					(size 1 1)
					(thickness 0.15)
				)
			)
		)
		(property "Author" "Antmicro"
			(at 0 0 0)
			(unlocked yes)
			(layer "F.Fab")
			(hide yes)
			(effects
				(font
					(size 1 1)
					(thickness 0.15)
				)
			)
		)
		(property "License" "Apache-2.0"
			(at 0 0 0)
			(unlocked yes)
			(layer "F.Fab")
			(hide yes)
			(effects
				(font
					(size 1 1)
					(thickness 0.15)
				)
			)
		)
		(sheetname "/DC-DC Converters/")
		(sheetfile "dc-dc_converters.kicad_sch")
		(attr through_hole)
		(fp_line
			(start -4.221 1.918)
			(end -4.221 10.38)
			(stroke
				(width 0.15)
				(type solid)
			)
			(layer "F.SilkS")
		)
		(fp_line
			(start -4.221 1.918)
			(end 1.719 1.918)
			(stroke
				(width 0.15)
				(type solid)
			)
			(layer "F.SilkS")
		)
		(fp_line
			(start -4.221 10.38)
			(end 1.719 10.38)
			(stroke
				(width 0.15)
				(type solid)
			)
			(layer "F.SilkS")
		)
		(fp_line
			(start 0.998 1.199)
			(end 1.699 1.199)
			(stroke
				(width 0.15)
				(type solid)
			)
			(layer "F.SilkS")
		)
		(fp_line
			(start 1.35 1.55)
			(end 1.35 0.848)
			(stroke
				(width 0.15)
				(type solid)
			)
			(layer "F.SilkS")
		)
		(fp_line
			(start 1.719 1.918)
			(end 1.719 10.38)
			(stroke
				(width 0.15)
				(type solid)
			)
			(layer "F.SilkS")
		)
		(fp_rect
			(start -4.721 -1.1)
			(end 2.219 12.1)
			(stroke
				(width 0.05)
				(type solid)
			)
			(fill no)
			(layer "F.CrtYd")
		)
		(fp_text user "License: Apache-2.0"
			(at -4.221 16.949 0)
			(layer "F.Fab")
			(effects
				(font
					(size 0.7 0.7)
					(thickness 0.15)
				)
				(justify left bottom)
			)
		)
		(fp_text user "Author: Antmicro"
			(at -4.221 15.749 0)
			(layer "F.Fab")
			(effects
				(font
					(size 0.7 0.7)
					(thickness 0.15)
				)
				(justify left bottom)
			)
		)
		(fp_text user "${REFERENCE}"
			(at -4.221 14.55 0)
			(layer "F.Fab")
			(effects
				(font
					(size 0.7 0.7)
					(thickness 0.15)
				)
				(justify left bottom)
			)
		)
		(pad "" np_thru_hole circle
			(at -2.5 7.179)
			(size 1.71 1.71)
			(drill 1.7)
			(layers "*.Cu" "*.Mask")
		)
		(pad "" np_thru_hole circle
			(at 0 7.179)
			(size 1.71 1.71)
			(drill 1.7)
			(layers "*.Cu" "*.Mask")
		)
		(pad "1" thru_hole circle
			(at 0 0)
			(size 2 2)
			(drill 1.3)
			(layers "*.Cu" "*.Mask")
			(remove_unused_layers no)
			(net 26 "Net-(D5-C)")
			(pintype "input")
		)
		(pad "2" thru_hole circle
			(at -2.5 0)
			(size 2 2)
			(drill 1.3)
			(layers "*.Cu" "*.Mask")
			(remove_unused_layers no)
			(net 2 "GND")
			(pintype "input")
		)
	)
	(footprint "antmicro-footprints:C_0402_1005Metric"
		(layer "F.Cu")
		(at 84.176 78.525 180)
		(descr "Capacitor SMD 0402")
		(tags "capacitor SMD 0402")
		(property "Reference" "C19"
			(at 1.239 -2.141 180)
			(layer "F.SilkS")
			(effects
				(font
					(size 0.7 0.7)
					(thickness 0.15)
				)
				(justify left bottom)
			)
		)
		(property "Value" "C_100n_50V_X8L_0402"
			(at -1.022927 2.155213 0)
			(layer "F.Fab")
			(effects
				(font
					(size 0.7 0.7)
					(thickness 0.15)
				)
				(justify right bottom)
			)
		)
		(property "Datasheet" "https://www.murata.com/products/productdetail?partno=GCM155L8EH104KE07%23"
			(at 0 0 180)
			(layer "F.Fab")
			(hide yes)
			(effects
				(font
					(size 1.27 1.27)
					(thickness 0.15)
				)
			)
		)
		(property "Description" "SMD Multilayer Ceramic Capacitor, 100nF, 50V, 0402, ±10%, X8L"
			(at 0 0 180)
			(layer "F.Fab")
			(hide yes)
			(effects
				(font
					(size 1.27 1.27)
					(thickness 0.15)
				)
			)
		)
		(property "MPN" "GCM155L8EH104KE07D"
			(at 0 0 180)
			(unlocked yes)
			(layer "F.Fab")
			(hide yes)
			(effects
				(font
					(size 1 1)
					(thickness 0.15)
				)
			)
		)
		(property "Val" "100n"
			(at 0 0 180)
			(unlocked yes)
			(layer "F.Fab")
			(hide yes)
			(effects
				(font
					(size 1 1)
					(thickness 0.15)
				)
			)
		)
		(property "Voltage" "50V"
			(at 0 0 180)
			(unlocked yes)
			(layer "F.Fab")
			(hide yes)
			(effects
				(font
					(size 1 1)
					(thickness 0.15)
				)
			)
		)
		(property "Dielectric" "X8L"
			(at 0 0 180)
			(unlocked yes)
			(layer "F.Fab")
			(hide yes)
			(effects
				(font
					(size 1 1)
					(thickness 0.15)
				)
			)
		)
		(property "Manufacturer" "Murata"
			(at 0 0 180)
			(unlocked yes)
			(layer "F.Fab")
			(hide yes)
			(effects
				(font
					(size 1 1)
					(thickness 0.15)
				)
			)
		)
		(property "License" "Apache-2.0"
			(at 0 0 180)
			(unlocked yes)
			(layer "F.Fab")
			(hide yes)
			(effects
				(font
					(size 1 1)
					(thickness 0.15)
				)
			)
		)
		(property "Author" "Antmicro"
			(at 0 0 180)
			(unlocked yes)
			(layer "F.Fab")
			(hide yes)
			(effects
				(font
					(size 1 1)
					(thickness 0.15)
				)
			)
		)
		(sheetname "/USB PD/")
		(sheetfile "usb_pd.kicad_sch")
		(attr smd)
		(fp_rect
			(start -0.925 -0.47)
			(end 0.925 0.47)
			(stroke
				(width 0.05)
				(type default)
			)
			(fill no)
			(layer "F.CrtYd")
		)
		(fp_line
			(start 0.504 0.248)
			(end -0.494 0.248)
			(stroke
				(width 0.15)
				(type solid)
			)
			(layer "F.Fab")
		)
		(fp_line
			(start 0.504 -0.25)
			(end 0.504 0.248)
			(stroke
				(width 0.15)
				(type solid)
			)
			(layer "F.Fab")
		)
		(fp_line
			(start -0.494 0.248)
			(end -0.494 -0.25)
			(stroke
				(width 0.15)
				(type solid)
			)
			(layer "F.Fab")
		)
		(fp_line
			(start -0.494 -0.25)
			(end 0.504 -0.25)
			(stroke
				(width 0.15)
				(type solid)
			)
			(layer "F.Fab")
		)
		(pad "1" smd roundrect
			(at -0.48 0 180)
			(size 0.59 0.64)
			(layers "F.Cu" "F.Mask" "F.Paste")
			(roundrect_rratio 0.25)
			(net 20 "Net-(C19-Pad1)")
			(pintype "passive")
		)
		(pad "2" smd roundrect
			(at 0.48 0 180)
			(size 0.59 0.64)
			(layers "F.Cu" "F.Mask" "F.Paste")
			(roundrect_rratio 0.25)
			(net 3 "VCC")
			(pintype "passive")
		)
	)
	(footprint "antmicro-footprints:C_0805_2012Metric"
		(layer "F.Cu")
		(at 89.2 84.7 90)
		(descr "Capacitor SMD 0805")
		(tags "capacitor SMD 0805")
		(property "Reference" "C4"
			(at -3.04 -5.004 90)
			(layer "F.SilkS")
			(effects
				(font
					(size 0.7 0.7)
					(thickness 0.15)
				)
				(justify left bottom)
			)
		)
		(property "Value" "C_10u_0805_35V"
			(at -2.055717 1.963152 90)
			(layer "F.Fab")
			(effects
				(font
					(size 0.7 0.7)
					(thickness 0.15)
				)
				(justify left bottom)
			)
		)
		(property "Datasheet" "https://www.murata.com/products/productdetail?partno=GRM21BR6YA106KE43%23"
			(at 0 0 90)
			(layer "F.Fab")
			(hide yes)
			(effects
				(font
					(size 1.27 1.27)
					(thickness 0.15)
				)
			)
		)
		(property "Description" "SMD Multilayer Ceramic Capacitor, 10 µF, 35 V, 0805 [2012 Metric], ± 10%, X5R, GRM Series"
			(at 0 0 90)
			(layer "F.Fab")
			(hide yes)
			(effects
				(font
					(size 1.27 1.27)
					(thickness 0.15)
				)
			)
		)
		(property "MPN" "GRM21BR6YA106KE43L"
			(at 0 0 90)
			(unlocked yes)
			(layer "F.Fab")
			(hide yes)
			(effects
				(font
					(size 1 1)
					(thickness 0.15)
				)
			)
		)
		(property "Manufacturer" "Murata"
			(at 0 0 90)
			(unlocked yes)
			(layer "F.Fab")
			(hide yes)
			(effects
				(font
					(size 1 1)
					(thickness 0.15)
				)
			)
		)
		(property "License" "Apache-2.0"
			(at 0 0 90)
			(unlocked yes)
			(layer "F.Fab")
			(hide yes)
			(effects
				(font
					(size 1 1)
					(thickness 0.15)
				)
			)
		)
		(property "Author" "Antmicro"
			(at 0 0 90)
			(unlocked yes)
			(layer "F.Fab")
			(hide yes)
			(effects
				(font
					(size 1 1)
					(thickness 0.15)
				)
			)
		)
		(property "Val" "10u"
			(at 0 0 90)
			(unlocked yes)
			(layer "F.Fab")
			(hide yes)
			(effects
				(font
					(size 1 1)
					(thickness 0.15)
				)
			)
		)
		(property "Voltage" "35V"
			(at 0 0 90)
			(unlocked yes)
			(layer "F.Fab")
			(hide yes)
			(effects
				(font
					(size 1 1)
					(thickness 0.15)
				)
			)
		)
		(property "Dielectric" ""
			(at 0 0 90)
			(unlocked yes)
			(layer "F.Fab")
			(hide yes)
			(effects
				(font
					(size 1 1)
					(thickness 0.15)
				)
			)
		)
		(property "Public" "False"
			(at 0 0 90)
			(unlocked yes)
			(layer "F.Fab")
			(hide yes)
			(effects
				(font
					(size 1 1)
					(thickness 0.15)
				)
			)
		)
		(sheetname "/DC-DC Converters/")
		(sheetfile "dc-dc_converters.kicad_sch")
		(attr smd)
		(fp_line
			(start -0.3 -0.7)
			(end 0.3 -0.7)
			(stroke
				(width 0.15)
				(type solid)
			)
			(layer "F.SilkS")
		)
		(fp_line
			(start -0.3 0.7)
			(end 0.3 0.7)
			(stroke
				(width 0.15)
				(type solid)
			)
			(layer "F.SilkS")
		)
		(fp_rect
			(start 1.95 -0.9)
			(end -1.95 0.9)
			(stroke
				(width 0.05)
				(type default)
			)
			(fill no)
			(layer "F.CrtYd")
		)
		(fp_rect
			(start -0.95 -0.675)
			(end 0.95 0.675)
			(stroke
				(width 0.15)
				(type solid)
			)
			(fill no)
			(layer "F.Fab")
		)
		(pad "1" smd roundrect
			(at -1.1 0 90)
			(size 1.2 1.3)
			(layers "F.Cu" "F.Mask" "F.Paste")
			(roundrect_rratio 0.25)
			(net 2 "GND")
			(pintype "passive")
		)
		(pad "2" smd roundrect
			(at 1.1 0 90)
			(size 1.2 1.3)
			(layers "F.Cu" "F.Mask" "F.Paste")
			(roundrect_rratio 0.25)
			(net 12 "Net-(U2-V_{CIN})")
			(pintype "passive")
		)
	)
	(footprint "antmicro-footprints:R_0402_1005Metric"
		(layer "F.Cu")
		(at 91.776 73.55 180)
		(descr "Resistor SMD 0402")
		(tags "resistor SMD 0402")
		(property "Reference" "R19"
			(at 1.126 -1.4 180)
			(layer "F.SilkS")
			(effects
				(font
					(size 0.7 0.7)
					(thickness 0.15)
				)
				(justify left bottom)
			)
		)
		(property "Value" "R_470R_0402"
			(at -1.011843 1.772047 180)
			(layer "F.Fab")
			(effects
				(font
					(size 0.7 0.7)
					(thickness 0.15)
				)
				(justify left bottom)
			)
		)
		(property "Datasheet" "https://www.bourns.com/docs/product-datasheets/cr.pdf"
			(at 0 0 180)
			(layer "F.Fab")
			(hide yes)
			(effects
				(font
					(size 1.27 1.27)
					(thickness 0.15)
				)
			)
		)
		(property "Description" "SMD Chip Resistor, 470 ohm, ± 1%, 62.5 mW, 0402 [1005 Metric], Thick Film, General Purpose"
			(at 0 0 180)
			(layer "F.Fab")
			(hide yes)
			(effects
				(font
					(size 1.27 1.27)
					(thickness 0.15)
				)
			)
		)
		(property "MPN" "CR0402-FX-4700GLF"
			(at 0 0 180)
			(unlocked yes)
			(layer "F.Fab")
			(hide yes)
			(effects
				(font
					(size 1 1)
					(thickness 0.15)
				)
			)
		)
		(property "Manufacturer" "Bourns"
			(at 0 0 180)
			(unlocked yes)
			(layer "F.Fab")
			(hide yes)
			(effects
				(font
					(size 1 1)
					(thickness 0.15)
				)
			)
		)
		(property "License" "Apache-2.0"
			(at 0 0 180)
			(unlocked yes)
			(layer "F.Fab")
			(hide yes)
			(effects
				(font
					(size 1 1)
					(thickness 0.15)
				)
			)
		)
		(property "Author" "Antmicro"
			(at 0 0 180)
			(unlocked yes)
			(layer "F.Fab")
			(hide yes)
			(effects
				(font
					(size 1 1)
					(thickness 0.15)
				)
			)
		)
		(property "Val" "470R"
			(at 0 0 180)
			(unlocked yes)
			(layer "F.Fab")
			(hide yes)
			(effects
				(font
					(size 1 1)
					(thickness 0.15)
				)
			)
		)
		(property "Tolerance" "1%"
			(at 0 0 180)
			(unlocked yes)
			(layer "F.Fab")
			(hide yes)
			(effects
				(font
					(size 1 1)
					(thickness 0.15)
				)
			)
		)
		(sheetname "/USB PD/")
		(sheetfile "usb_pd.kicad_sch")
		(attr smd)
		(fp_rect
			(start -0.925 -0.47)
			(end 0.925 0.47)
			(stroke
				(width 0.05)
				(type default)
			)
			(fill no)
			(layer "F.CrtYd")
		)
		(fp_rect
			(start -0.5 -0.25)
			(end 0.5 0.25)
			(stroke
				(width 0.15)
				(type solid)
			)
			(fill no)
			(layer "F.Fab")
		)
		(pad "1" smd roundrect
			(at -0.48 0 180)
			(size 0.59 0.64)
			(layers "F.Cu" "F.Mask" "F.Paste")
			(roundrect_rratio 0.25)
			(net 63 "Net-(D1-C)")
			(pintype "passive")
		)
		(pad "2" smd roundrect
			(at 0.48 0 180)
			(size 0.59 0.64)
			(layers "F.Cu" "F.Mask" "F.Paste")
			(roundrect_rratio 0.25)
			(net 6 "VBUS")
			(pintype "passive")
		)
	)
	(footprint "antmicro-footprints:C_Pol_Vishay-T59-EE"
		(layer "F.Cu")
		(at 84.676 95.55 -90)
		(property "Reference" "C44"
			(at -5.6 1.276 0)
			(unlocked yes)
			(layer "F.SilkS")
			(effects
				(font
					(size 0.7 0.7)
					(thickness 0.15)
				)
				(justify left bottom)
			)
		)
		(property "Value" "C_Pol_150u_30V_Vishay-T59-EE"
			(at -5.08 5.08 270)
			(unlocked yes)
			(layer "F.Fab")
			(effects
				(font
					(size 0.7 0.7)
					(thickness 0.15)
				)
				(justify left bottom)
			)
		)
		(property "Datasheet" "https://www.vishay.com/docs/40191/t59.pdf"
			(at 0 0 270)
			(layer "F.Fab")
			(hide yes)
			(effects
				(font
					(size 1.27 1.27)
					(thickness 0.15)
				)
			)
		)
		(property "Description" "Tantalum Capacitors - Polymer 150uF 30volts 20% 75mohms maxESR"
			(at 0 0 270)
			(layer "F.Fab")
			(hide yes)
			(effects
				(font
					(size 1.27 1.27)
					(thickness 0.15)
				)
			)
		)
		(property "MPN" "T59EE157M030C0075"
			(at 0 0 270)
			(unlocked yes)
			(layer "F.Fab")
			(hide yes)
			(effects
				(font
					(size 1 1)
					(thickness 0.15)
				)
			)
		)
		(property "Manufacturer" "Vishay"
			(at 0 0 270)
			(unlocked yes)
			(layer "F.Fab")
			(hide yes)
			(effects
				(font
					(size 1 1)
					(thickness 0.15)
				)
			)
		)
		(property "Voltage" "30V"
			(at 0 0 270)
			(unlocked yes)
			(layer "F.Fab")
			(hide yes)
			(effects
				(font
					(size 1 1)
					(thickness 0.15)
				)
			)
		)
		(property "Val" "150u"
			(at 0 0 270)
			(unlocked yes)
			(layer "F.Fab")
			(hide yes)
			(effects
				(font
					(size 1 1)
					(thickness 0.15)
				)
			)
		)
		(property "Author" "Antmicro"
			(at 0 0 270)
			(unlocked yes)
			(layer "F.Fab")
			(hide yes)
			(effects
				(font
					(size 1 1)
					(thickness 0.15)
				)
			)
		)
		(property "License" "Apache-2.0"
			(at 0 0 270)
			(unlocked yes)
			(layer "F.Fab")
			(hide yes)
			(effects
				(font
					(size 1 1)
					(thickness 0.15)
				)
			)
		)
		(property "Dielectric" "template_dielectric"
			(at 0 0 270)
			(unlocked yes)
			(layer "F.Fab")
			(hide yes)
			(effects
				(font
					(size 1 1)
					(thickness 0.15)
				)
			)
		)
		(sheetname "/DC-DC Converters/")
		(sheetfile "dc-dc_converters.kicad_sch")
		(attr smd)
		(fp_line
			(start -2 2.25)
			(end 2 2.25)
			(stroke
				(width 0.15)
				(type solid)
			)
			(layer "F.SilkS")
		)
		(fp_line
			(start -2 -2.25)
			(end 2 -2.25)
			(stroke
				(width 0.15)
				(type solid)
			)
			(layer "F.SilkS")
		)
		(fp_line
			(start -3.5 -2.8)
			(end -3.5 -3.2)
			(stroke
				(width 0.15)
				(type solid)
			)
			(layer "F.SilkS")
		)
		(fp_line
			(start -3.7 -3)
			(end -3.3 -3)
			(stroke
				(width 0.15)
				(type solid)
			)
			(layer "F.SilkS")
		)
		(fp_rect
			(start -4.9 -2.9)
			(end 4.9 2.9)
			(stroke
				(width 0.05)
				(type solid)
			)
			(fill no)
			(layer "F.CrtYd")
		)
		(fp_rect
			(start -3.75 -2.25)
			(end 3.75 2.25)
			(stroke
				(width 0.15)
				(type solid)
			)
			(fill no)
			(layer "F.Fab")
		)
		(pad "1" smd trapezoid
			(at -3.4 0 270)
			(size 2.5 5.3)
			(layers "F.Cu" "F.Mask" "F.Paste")
			(net 12 "Net-(U2-V_{CIN})")
			(pintype "passive")
		)
		(pad "2" smd trapezoid
			(at 3.4 0 270)
			(size 2.5 5.3)
			(layers "F.Cu" "F.Mask" "F.Paste")
			(net 2 "GND")
			(pintype "passive")
		)
	)
	(footprint "antmicro-footprints:R_0402_1005Metric"
		(layer "F.Cu")
		(at 97.826 72.35 90)
		(descr "Resistor SMD 0402")
		(tags "resistor SMD 0402")
		(property "Reference" "R34"
			(at -10 0.55 0)
			(layer "B.SilkS")
			(effects
				(font
					(size 0.7 0.7)
					(thickness 0.15)
				)
				(justify left bottom mirror)
			)
		)
		(property "Value" "R_1k2_0402"
			(at -1.011843 1.772047 90)
			(layer "F.Fab")
			(effects
				(font
					(size 0.7 0.7)
					(thickness 0.15)
				)
				(justify left bottom)
			)
		)
		(property "Datasheet" "https://www.bourns.com/docs/product-datasheets/cr.pdf"
			(at 0 0 90)
			(layer "F.Fab")
			(hide yes)
			(effects
				(font
					(size 1.27 1.27)
					(thickness 0.15)
				)
			)
		)
		(property "Description" "SMD Chip Resistor, 1.2 kohm, ± 1%, 62.5 mW, 0402 [1005 Metric], Thick Film, General Purpose"
			(at 0 0 90)
			(layer "F.Fab")
			(hide yes)
			(effects
				(font
					(size 1.27 1.27)
					(thickness 0.15)
				)
			)
		)
		(property "MPN" "CR0402-FX-1201GLF"
			(at 0 0 90)
			(unlocked yes)
			(layer "F.Fab")
			(hide yes)
			(effects
				(font
					(size 1 1)
					(thickness 0.15)
				)
			)
		)
		(property "Manufacturer" "Bourns"
			(at 0 0 90)
			(unlocked yes)
			(layer "F.Fab")
			(hide yes)
			(effects
				(font
					(size 1 1)
					(thickness 0.15)
				)
			)
		)
		(property "License" "Apache-2.0"
			(at 0 0 90)
			(unlocked yes)
			(layer "F.Fab")
			(hide yes)
			(effects
				(font
					(size 1 1)
					(thickness 0.15)
				)
			)
		)
		(property "Author" "Antmicro"
			(at 0 0 90)
			(unlocked yes)
			(layer "F.Fab")
			(hide yes)
			(effects
				(font
					(size 1 1)
					(thickness 0.15)
				)
			)
		)
		(property "Val" "1k2"
			(at 0 0 90)
			(unlocked yes)
			(layer "F.Fab")
			(hide yes)
			(effects
				(font
					(size 1 1)
					(thickness 0.15)
				)
			)
		)
		(property "Tolerance" "1%"
			(at 0 0 90)
			(unlocked yes)
			(layer "F.Fab")
			(hide yes)
			(effects
				(font
					(size 1 1)
					(thickness 0.15)
				)
			)
		)
		(sheetname "/USB PD/")
		(sheetfile "usb_pd.kicad_sch")
		(attr smd)
		(fp_rect
			(start -0.925 -0.47)
			(end 0.925 0.47)
			(stroke
				(width 0.05)
				(type default)
			)
			(fill no)
			(layer "F.CrtYd")
		)
		(fp_rect
			(start -0.5 -0.25)
			(end 0.5 0.25)
			(stroke
				(width 0.15)
				(type solid)
			)
			(fill no)
			(layer "F.Fab")
		)
		(pad "1" smd roundrect
			(at -0.48 0 90)
			(size 0.59 0.64)
			(layers "F.Cu" "F.Mask" "F.Paste")
			(roundrect_rratio 0.25)
			(net 64 "Net-(D3-A)")
			(pintype "passive")
		)
		(pad "2" smd roundrect
			(at 0.48 0 90)
			(size 0.59 0.64)
			(layers "F.Cu" "F.Mask" "F.Paste")
			(roundrect_rratio 0.25)
			(net 6 "VBUS")
			(pintype "passive")
		)
	)
	(footprint "antmicro-footprints:R_0402_1005Metric"
		(layer "F.Cu")
		(at 86.026 78.525 180)
		(descr "Resistor SMD 0402")
		(tags "resistor SMD 0402")
		(property "Reference" "R33"
			(at 1.057 -2.141 0)
			(layer "F.SilkS")
			(effects
				(font
					(size 0.7 0.7)
					(thickness 0.15)
				)
				(justify left bottom)
			)
		)
		(property "Value" "R_100R_0402"
			(at -1.011843 1.772047 0)
			(layer "F.Fab")
			(effects
				(font
					(size 0.7 0.7)
					(thickness 0.15)
				)
				(justify right bottom)
			)
		)
		(property "Datasheet" "https://www.bourns.com/docs/product-datasheets/cr.pdf"
			(at 0 0 180)
			(layer "F.Fab")
			(hide yes)
			(effects
				(font
					(size 1.27 1.27)
					(thickness 0.15)
				)
			)
		)
		(property "Description" "SMD Chip Resistor, 100 ohm, ± 1%, 62.5 mW, 0402 [1005 Metric], Thick Film, General Purpose"
			(at 0 0 180)
			(layer "F.Fab")
			(hide yes)
			(effects
				(font
					(size 1.27 1.27)
					(thickness 0.15)
				)
			)
		)
		(property "MPN" "CR0402-FX-1000GLF"
			(at 0 0 180)
			(unlocked yes)
			(layer "F.Fab")
			(hide yes)
			(effects
				(font
					(size 1 1)
					(thickness 0.15)
				)
			)
		)
		(property "Manufacturer" "Bourns"
			(at 0 0 180)
			(unlocked yes)
			(layer "F.Fab")
			(hide yes)
			(effects
				(font
					(size 1 1)
					(thickness 0.15)
				)
			)
		)
		(property "License" "Apache-2.0"
			(at 0 0 180)
			(unlocked yes)
			(layer "F.Fab")
			(hide yes)
			(effects
				(font
					(size 1 1)
					(thickness 0.15)
				)
			)
		)
		(property "Author" "Antmicro"
			(at 0 0 180)
			(unlocked yes)
			(layer "F.Fab")
			(hide yes)
			(effects
				(font
					(size 1 1)
					(thickness 0.15)
				)
			)
		)
		(property "Val" "100R"
			(at 0 0 180)
			(unlocked yes)
			(layer "F.Fab")
			(hide yes)
			(effects
				(font
					(size 1 1)
					(thickness 0.15)
				)
			)
		)
		(property "Tolerance" "1%"
			(at 0 0 180)
			(unlocked yes)
			(layer "F.Fab")
			(hide yes)
			(effects
				(font
					(size 1 1)
					(thickness 0.15)
				)
			)
		)
		(sheetname "/USB PD/")
		(sheetfile "usb_pd.kicad_sch")
		(attr smd)
		(fp_rect
			(start -0.925 -0.47)
			(end 0.925 0.47)
			(stroke
				(width 0.05)
				(type default)
			)
			(fill no)
			(layer "F.CrtYd")
		)
		(fp_rect
			(start -0.5 -0.25)
			(end 0.5 0.25)
			(stroke
				(width 0.15)
				(type solid)
			)
			(fill no)
			(layer "F.Fab")
		)
		(pad "1" smd roundrect
			(at -0.48 0 180)
			(size 0.59 0.64)
			(layers "F.Cu" "F.Mask" "F.Paste")
			(roundrect_rratio 0.25)
			(net 7 "Net-(Q1-G)")
			(pintype "passive")
		)
		(pad "2" smd roundrect
			(at 0.48 0 180)
			(size 0.59 0.64)
			(layers "F.Cu" "F.Mask" "F.Paste")
			(roundrect_rratio 0.25)
			(net 20 "Net-(C19-Pad1)")
			(pintype "passive")
		)
	)
	(footprint "antmicro-footprints:C_0402_1005Metric"
		(layer "F.Cu")
		(at 100 79.577 180)
		(descr "Capacitor SMD 0402")
		(tags "capacitor SMD 0402")
		(property "Reference" "C1"
			(at -1.092 -0.433 0)
			(layer "F.SilkS")
			(effects
				(font
					(size 0.7 0.7)
					(thickness 0.15)
				)
				(justify left bottom)
			)
		)
		(property "Value" "C_1u_25V_0402"
			(at -1.022927 2.155213 0)
			(layer "F.Fab")
			(effects
				(font
					(size 0.7 0.7)
					(thickness 0.15)
				)
				(justify right bottom)
			)
		)
		(property "Datasheet" "https://www.murata.com/products/productdetail?partno=GRM155R61E105KE11%23"
			(at 0 0 180)
			(layer "F.Fab")
			(hide yes)
			(effects
				(font
					(size 1.27 1.27)
					(thickness 0.15)
				)
			)
		)
		(property "Description" "SMD Multilayer Ceramic Capacitor, 1 µF, 25 V, 0402 [1005 Metric], ± 10%, X5R, GRM Series"
			(at 0 0 180)
			(layer "F.Fab")
			(hide yes)
			(effects
				(font
					(size 1.27 1.27)
					(thickness 0.15)
				)
			)
		)
		(property "MPN" "GRM155R61E105KE11J"
			(at 0 0 180)
			(unlocked yes)
			(layer "F.Fab")
			(hide yes)
			(effects
				(font
					(size 1 1)
					(thickness 0.15)
				)
			)
		)
		(property "Manufacturer" "Murata"
			(at 0 0 180)
			(unlocked yes)
			(layer "F.Fab")
			(hide yes)
			(effects
				(font
					(size 1 1)
					(thickness 0.15)
				)
			)
		)
		(property "License" "Apache-2.0"
			(at 0 0 180)
			(unlocked yes)
			(layer "F.Fab")
			(hide yes)
			(effects
				(font
					(size 1 1)
					(thickness 0.15)
				)
			)
		)
		(property "Author" "Antmicro"
			(at 0 0 180)
			(unlocked yes)
			(layer "F.Fab")
			(hide yes)
			(effects
				(font
					(size 1 1)
					(thickness 0.15)
				)
			)
		)
		(property "Val" "1u"
			(at 0 0 180)
			(unlocked yes)
			(layer "F.Fab")
			(hide yes)
			(effects
				(font
					(size 1 1)
					(thickness 0.15)
				)
			)
		)
		(property "Voltage" "25V"
			(at 0 0 180)
			(unlocked yes)
			(layer "F.Fab")
			(hide yes)
			(effects
				(font
					(size 1 1)
					(thickness 0.15)
				)
			)
		)
		(property "Dielectric" "X5R"
			(at 0 0 180)
			(unlocked yes)
			(layer "F.Fab")
			(hide yes)
			(effects
				(font
					(size 1 1)
					(thickness 0.15)
				)
			)
		)
		(sheetname "/DC-DC Converters/")
		(sheetfile "dc-dc_converters.kicad_sch")
		(attr smd)
		(fp_rect
			(start -0.925 -0.47)
			(end 0.925 0.47)
			(stroke
				(width 0.05)
				(type default)
			)
			(fill no)
			(layer "F.CrtYd")
		)
		(fp_line
			(start 0.504 0.248)
			(end -0.494 0.248)
			(stroke
				(width 0.15)
				(type solid)
			)
			(layer "F.Fab")
		)
		(fp_line
			(start 0.504 -0.25)
			(end 0.504 0.248)
			(stroke
				(width 0.15)
				(type solid)
			)
			(layer "F.Fab")
		)
		(fp_line
			(start -0.494 0.248)
			(end -0.494 -0.25)
			(stroke
				(width 0.15)
				(type solid)
			)
			(layer "F.Fab")
		)
		(fp_line
			(start -0.494 -0.25)
			(end 0.504 -0.25)
			(stroke
				(width 0.15)
				(type solid)
			)
			(layer "F.Fab")
		)
		(pad "1" smd roundrect
			(at -0.48 0 180)
			(size 0.59 0.64)
			(layers "F.Cu" "F.Mask" "F.Paste")
			(roundrect_rratio 0.25)
			(net 2 "GND")
			(pintype "passive")
		)
		(pad "2" smd roundrect
			(at 0.48 0 180)
			(size 0.59 0.64)
			(layers "F.Cu" "F.Mask" "F.Paste")
			(roundrect_rratio 0.25)
			(net 10 "/DC-DC Converters/VDD_12V_DCDC")
			(pintype "passive")
		)
	)
	(footprint "antmicro-footprints:R_0402_1005Metric"
		(layer "F.Cu")
		(at 88.9 68.63 -90)
		(descr "Resistor SMD 0402")
		(tags "resistor SMD 0402")
		(property "Reference" "R38"
			(at -1.205 -1.251 270)
			(layer "F.SilkS")
			(effects
				(font
					(size 0.7 0.7)
					(thickness 0.15)
				)
				(justify right bottom)
			)
		)
		(property "Value" "R_0R_0402"
			(at -1.011843 1.772047 90)
			(layer "F.Fab")
			(effects
				(font
					(size 0.7 0.7)
					(thickness 0.15)
				)
				(justify right bottom)
			)
		)
		(property "Datasheet" "https://industrial.panasonic.com/cdbs/www-data/pdf/RDA0000/AOA0000C301.pdf"
			(at 0 0 270)
			(layer "F.Fab")
			(hide yes)
			(effects
				(font
					(size 1.27 1.27)
					(thickness 0.15)
				)
			)
		)
		(property "Description" "SMD Chip Resistor, Jumper, 0 ohm, 100 mW, 0402 [1005 Metric], Thick Film, General Purpose"
			(at 0 0 270)
			(layer "F.Fab")
			(hide yes)
			(effects
				(font
					(size 1.27 1.27)
					(thickness 0.15)
				)
			)
		)
		(property "MPN" "ERJ2GE0R00X"
			(at 0 0 270)
			(unlocked yes)
			(layer "F.Fab")
			(hide yes)
			(effects
				(font
					(size 1 1)
					(thickness 0.15)
				)
			)
		)
		(property "Manufacturer" "Panasonic"
			(at 0 0 270)
			(unlocked yes)
			(layer "F.Fab")
			(hide yes)
			(effects
				(font
					(size 1 1)
					(thickness 0.15)
				)
			)
		)
		(property "License" "Apache-2.0"
			(at 0 0 270)
			(unlocked yes)
			(layer "F.Fab")
			(hide yes)
			(effects
				(font
					(size 1 1)
					(thickness 0.15)
				)
			)
		)
		(property "Author" "Antmicro"
			(at 0 0 270)
			(unlocked yes)
			(layer "F.Fab")
			(hide yes)
			(effects
				(font
					(size 1 1)
					(thickness 0.15)
				)
			)
		)
		(property "Val" "0R"
			(at 0 0 270)
			(unlocked yes)
			(layer "F.Fab")
			(hide yes)
			(effects
				(font
					(size 1 1)
					(thickness 0.15)
				)
			)
		)
		(property "Tolerance" ""
			(at 0 0 270)
			(unlocked yes)
			(layer "F.Fab")
			(hide yes)
			(effects
				(font
					(size 1 1)
					(thickness 0.15)
				)
			)
		)
		(property "Current" "1A"
			(at 0 0 270)
			(unlocked yes)
			(layer "F.Fab")
			(hide yes)
			(effects
				(font
					(size 1 1)
					(thickness 0.15)
				)
			)
		)
		(sheetname "/USB PD/")
		(sheetfile "usb_pd.kicad_sch")
		(attr smd exclude_from_pos_files exclude_from_bom dnp)
		(fp_rect
			(start -0.925 -0.47)
			(end 0.925 0.47)
			(stroke
				(width 0.05)
				(type default)
			)
			(fill no)
			(layer "F.CrtYd")
		)
		(fp_rect
			(start -0.5 -0.25)
			(end 0.5 0.25)
			(stroke
				(width 0.15)
				(type solid)
			)
			(fill no)
			(layer "F.Fab")
		)
		(pad "1" smd roundrect
			(at -0.48 0 270)
			(size 0.59 0.64)
			(layers "F.Cu" "F.Mask" "F.Paste")
			(roundrect_rratio 0.25)
			(net 61 "/USB PD/QWIIC_VCC")
			(pintype "passive")
		)
		(pad "2" smd roundrect
			(at 0.48 0 270)
			(size 0.59 0.64)
			(layers "F.Cu" "F.Mask" "F.Paste")
			(roundrect_rratio 0.25)
			(net 1 "+3V3")
			(pintype "passive")
		)
	)
	(footprint "antmicro-footprints:R_0402_1005Metric"
		(layer "F.Cu")
		(at 100.276 72.35 90)
		(descr "Resistor SMD 0402")
		(tags "resistor SMD 0402")
		(property "Reference" "R26"
			(at -7.9 -1.8 0)
			(layer "B.SilkS")
			(effects
				(font
					(size 0.7 0.7)
					(thickness 0.15)
				)
				(justify left bottom mirror)
			)
		)
		(property "Value" "R_470_0402"
			(at -1.011843 1.772047 90)
			(layer "F.Fab")
			(effects
				(font
					(size 0.7 0.7)
					(thickness 0.15)
				)
				(justify left bottom)
			)
		)
		(property "Datasheet" "https://www.bourns.com/docs/product-datasheets/cr.pdf"
			(at 0 0 90)
			(layer "F.Fab")
			(hide yes)
			(effects
				(font
					(size 1.27 1.27)
					(thickness 0.15)
				)
			)
		)
		(property "Description" "SMD Chip Resistor, 470 ohm, ± 1%, 62.5 mW, 0402 [1005 Metric], Thick Film, General Purpose"
			(at 0 0 90)
			(layer "F.Fab")
			(hide yes)
			(effects
				(font
					(size 1.27 1.27)
					(thickness 0.15)
				)
			)
		)
		(property "MPN" "CR0402-FX-4700GLF"
			(at 0 0 90)
			(unlocked yes)
			(layer "F.Fab")
			(hide yes)
			(effects
				(font
					(size 1 1)
					(thickness 0.15)
				)
			)
		)
		(property "Manufacturer" "Bourns"
			(at 0 0 90)
			(unlocked yes)
			(layer "F.Fab")
			(hide yes)
			(effects
				(font
					(size 1 1)
					(thickness 0.15)
				)
			)
		)
		(property "License" "Apache-2.0"
			(at 0 0 90)
			(unlocked yes)
			(layer "F.Fab")
			(hide yes)
			(effects
				(font
					(size 1 1)
					(thickness 0.15)
				)
			)
		)
		(property "Author" "Antmicro"
			(at 0 0 90)
			(unlocked yes)
			(layer "F.Fab")
			(hide yes)
			(effects
				(font
					(size 1 1)
					(thickness 0.15)
				)
			)
		)
		(property "Val" "470R"
			(at 0 0 90)
			(unlocked yes)
			(layer "F.Fab")
			(hide yes)
			(effects
				(font
					(size 1 1)
					(thickness 0.15)
				)
			)
		)
		(property "Tolerance" "1%"
			(at 0 0 90)
			(unlocked yes)
			(layer "F.Fab")
			(hide yes)
			(effects
				(font
					(size 1 1)
					(thickness 0.15)
				)
			)
		)
		(sheetname "/USB PD/")
		(sheetfile "usb_pd.kicad_sch")
		(attr smd)
		(fp_rect
			(start -0.925 -0.47)
			(end 0.925 0.47)
			(stroke
				(width 0.05)
				(type default)
			)
			(fill no)
			(layer "F.CrtYd")
		)
		(fp_rect
			(start -0.5 -0.25)
			(end 0.5 0.25)
			(stroke
				(width 0.15)
				(type solid)
			)
			(fill no)
			(layer "F.Fab")
		)
		(pad "1" smd roundrect
			(at -0.48 0 90)
			(size 0.59 0.64)
			(layers "F.Cu" "F.Mask" "F.Paste")
			(roundrect_rratio 0.25)
			(net 67 "Net-(D7-A)")
			(pintype "passive")
		)
		(pad "2" smd roundrect
			(at 0.48 0 90)
			(size 0.59 0.64)
			(layers "F.Cu" "F.Mask" "F.Paste")
			(roundrect_rratio 0.25)
			(net 25 "+5V")
			(pintype "passive")
		)
	)
	(footprint "antmicro-footprints:C_0402_1005Metric"
		(layer "B.Cu")
		(at 86.45 80.5 -90)
		(descr "Capacitor SMD 0402")
		(tags "capacitor SMD 0402")
		(property "Reference" "C24"
			(at -3.157 -0.429 90)
			(layer "B.SilkS")
			(effects
				(font
					(size 0.7 0.7)
					(thickness 0.15)
				)
				(justify left bottom mirror)
			)
		)
		(property "Value" "C_100n_50V_X8L_0402"
			(at -1.022927 -2.155213 90)
			(layer "B.Fab")
			(effects
				(font
					(size 0.7 0.7)
					(thickness 0.15)
				)
				(justify left bottom mirror)
			)
		)
		(property "Datasheet" "https://www.murata.com/products/productdetail?partno=GCM155L8EH104KE07%23"
			(at 0 0 270)
			(layer "F.Fab")
			(hide yes)
			(effects
				(font
					(size 1.27 1.27)
					(thickness 0.15)
				)
			)
		)
		(property "Description" "SMD Multilayer Ceramic Capacitor, 100nF, 50V, 0402, ±10%, X8L"
			(at 0 0 270)
			(layer "F.Fab")
			(hide yes)
			(effects
				(font
					(size 1.27 1.27)
					(thickness 0.15)
				)
			)
		)
		(property "MPN" "GCM155L8EH104KE07D"
			(at 0 0 270)
			(unlocked yes)
			(layer "B.Fab")
			(hide yes)
			(effects
				(font
					(size 1 1)
					(thickness 0.15)
				)
				(justify mirror)
			)
		)
		(property "Val" "100n"
			(at 0 0 270)
			(unlocked yes)
			(layer "B.Fab")
			(hide yes)
			(effects
				(font
					(size 1 1)
					(thickness 0.15)
				)
				(justify mirror)
			)
		)
		(property "Voltage" "50V"
			(at 0 0 270)
			(unlocked yes)
			(layer "B.Fab")
			(hide yes)
			(effects
				(font
					(size 1 1)
					(thickness 0.15)
				)
				(justify mirror)
			)
		)
		(property "Dielectric" "X8L"
			(at 0 0 270)
			(unlocked yes)
			(layer "B.Fab")
			(hide yes)
			(effects
				(font
					(size 1 1)
					(thickness 0.15)
				)
				(justify mirror)
			)
		)
		(property "Manufacturer" "Murata"
			(at 0 0 270)
			(unlocked yes)
			(layer "B.Fab")
			(hide yes)
			(effects
				(font
					(size 1 1)
					(thickness 0.15)
				)
				(justify mirror)
			)
		)
		(property "License" "Apache-2.0"
			(at 0 0 270)
			(unlocked yes)
			(layer "B.Fab")
			(hide yes)
			(effects
				(font
					(size 1 1)
					(thickness 0.15)
				)
				(justify mirror)
			)
		)
		(property "Author" "Antmicro"
			(at 0 0 270)
			(unlocked yes)
			(layer "B.Fab")
			(hide yes)
			(effects
				(font
					(size 1 1)
					(thickness 0.15)
				)
				(justify mirror)
			)
		)
		(sheetname "/DC-DC Converters/")
		(sheetfile "dc-dc_converters.kicad_sch")
		(attr smd)
		(fp_rect
			(start -0.925 0.47)
			(end 0.925 -0.47)
			(stroke
				(width 0.05)
				(type default)
			)
			(fill no)
			(layer "B.CrtYd")
		)
		(fp_line
			(start -0.494 0.25)
			(end -0.494 -0.248)
			(stroke
				(width 0.15)
				(type solid)
			)
			(layer "B.Fab")
		)
		(fp_line
			(start 0.504 0.25)
			(end -0.494 0.25)
			(stroke
				(width 0.15)
				(type solid)
			)
			(layer "B.Fab")
		)
		(fp_line
			(start -0.494 -0.248)
			(end 0.504 -0.248)
			(stroke
				(width 0.15)
				(type solid)
			)
			(layer "B.Fab")
		)
		(fp_line
			(start 0.504 -0.248)
			(end 0.504 0.25)
			(stroke
				(width 0.15)
				(type solid)
			)
			(layer "B.Fab")
		)
		(pad "1" smd roundrect
			(at -0.48 0 270)
			(size 0.59 0.64)
			(layers "B.Cu" "B.Mask" "B.Paste")
			(roundrect_rratio 0.25)
			(net 23 "Net-(U4-SW)")
			(pintype "passive")
		)
		(pad "2" smd roundrect
			(at 0.48 0 270)
			(size 0.59 0.64)
			(layers "B.Cu" "B.Mask" "B.Paste")
			(roundrect_rratio 0.25)
			(net 24 "Net-(U4-BST)")
			(pintype "passive")
		)
	)
	(footprint "antmicro-footprints:R_0402_1005Metric"
		(layer "B.Cu")
		(at 87.626 89.1 90)
		(descr "Resistor SMD 0402")
		(tags "resistor SMD 0402")
		(property "Reference" "R2"
			(at 0.85 2.75 90)
			(layer "B.SilkS")
			(effects
				(font
					(size 0.7 0.7)
					(thickness 0.15)
				)
				(justify left bottom mirror)
			)
		)
		(property "Value" "R_5k23_0402"
			(at -1.011843 -1.772047 90)
			(layer "B.Fab")
			(effects
				(font
					(size 0.7 0.7)
					(thickness 0.15)
				)
				(justify right bottom mirror)
			)
		)
		(property "Datasheet" "https://www.farnell.com/datasheets/3795017.pdf"
			(at 0 0 90)
			(layer "F.Fab")
			(hide yes)
			(effects
				(font
					(size 1.27 1.27)
					(thickness 0.15)
				)
			)
		)
		(property "Description" "SMD Chip Resistor, 5.23 kohm, ± 1%, 63 mW, 0402 [1005 Metric], Thick Film, General Purpose"
			(at 0 0 90)
			(layer "F.Fab")
			(hide yes)
			(effects
				(font
					(size 1.27 1.27)
					(thickness 0.15)
				)
			)
		)
		(property "MPN" "RC0402FR-075K23L"
			(at 0 0 90)
			(unlocked yes)
			(layer "B.Fab")
			(hide yes)
			(effects
				(font
					(size 1 1)
					(thickness 0.15)
				)
				(justify mirror)
			)
		)
		(property "Manufacturer" "YAGEO"
			(at 0 0 90)
			(unlocked yes)
			(layer "B.Fab")
			(hide yes)
			(effects
				(font
					(size 1 1)
					(thickness 0.15)
				)
				(justify mirror)
			)
		)
		(property "License" "Apache-2.0"
			(at 0 0 90)
			(unlocked yes)
			(layer "B.Fab")
			(hide yes)
			(effects
				(font
					(size 1 1)
					(thickness 0.15)
				)
				(justify mirror)
			)
		)
		(property "Author" "Antmicro"
			(at 0 0 90)
			(unlocked yes)
			(layer "B.Fab")
			(hide yes)
			(effects
				(font
					(size 1 1)
					(thickness 0.15)
				)
				(justify mirror)
			)
		)
		(property "Val" "5k23"
			(at 0 0 90)
			(unlocked yes)
			(layer "B.Fab")
			(hide yes)
			(effects
				(font
					(size 1 1)
					(thickness 0.15)
				)
				(justify mirror)
			)
		)
		(property "Tolerance" "1%"
			(at 0 0 90)
			(unlocked yes)
			(layer "B.Fab")
			(hide yes)
			(effects
				(font
					(size 1 1)
					(thickness 0.15)
				)
				(justify mirror)
			)
		)
		(sheetname "/DC-DC Converters/")
		(sheetfile "dc-dc_converters.kicad_sch")
		(attr smd)
		(fp_rect
			(start -0.925 0.47)
			(end 0.925 -0.47)
			(stroke
				(width 0.05)
				(type default)
			)
			(fill no)
			(layer "B.CrtYd")
		)
		(fp_rect
			(start -0.5 0.25)
			(end 0.5 -0.25)
			(stroke
				(width 0.15)
				(type solid)
			)
			(fill no)
			(layer "B.Fab")
		)
		(pad "1" smd roundrect
			(at -0.48 0 90)
			(size 0.59 0.64)
			(layers "B.Cu" "B.Mask" "B.Paste")
			(roundrect_rratio 0.25)
			(net 25 "+5V")
			(pintype "passive")
		)
		(pad "2" smd roundrect
			(at 0.48 0 90)
			(size 0.59 0.64)
			(layers "B.Cu" "B.Mask" "B.Paste")
			(roundrect_rratio 0.25)
			(net 40 "Net-(U3-FB)")
			(pintype "passive")
		)
	)
	(footprint "antmicro-footprints:L_1008_2520Metric"
		(layer "B.Cu")
		(at 83.876 86.45 180)
		(descr "Inductor SMD 1008 (2520 Metric)")
		(tags "inductor")
		(property "Reference" "L2"
			(at -3.2 0.8 0)
			(layer "B.SilkS")
			(effects
				(font
					(size 0.7 0.7)
					(thickness 0.15)
				)
				(justify left bottom mirror)
			)
		)
		(property "Value" "L_3u3_2.5A_1008"
			(at 0 -2.5 0)
			(layer "B.Fab")
			(effects
				(font
					(size 0.7 0.7)
					(thickness 0.15)
				)
				(justify left bottom mirror)
			)
		)
		(property "Datasheet" "https://product.tdk.com/system/files/dam/doc/product/inductor/inductor/smd/catalog/inductor_automotive_power_tfm252012alma_en.pdf"
			(at 0 0 180)
			(layer "F.Fab")
			(hide yes)
			(effects
				(font
					(size 1.27 1.27)
					(thickness 0.15)
				)
			)
		)
		(property "Description" "3.3 µH Shielded Thin Film Inductor 2 A 140mOhm Max 1008 (2520 Metric)"
			(at 0 0 180)
			(layer "F.Fab")
			(hide yes)
			(effects
				(font
					(size 1.27 1.27)
					(thickness 0.15)
				)
			)
		)
		(property "MPN" "TFM252012ALMA3R3MTAA"
			(at 0 0 180)
			(unlocked yes)
			(layer "B.Fab")
			(hide yes)
			(effects
				(font
					(size 1 1)
					(thickness 0.15)
				)
				(justify mirror)
			)
		)
		(property "ISat" "2.1 A"
			(at 0 0 180)
			(unlocked yes)
			(layer "B.Fab")
			(hide yes)
			(effects
				(font
					(size 1 1)
					(thickness 0.15)
				)
				(justify mirror)
			)
		)
		(property "IMax" "2.5 A"
			(at 0 0 180)
			(unlocked yes)
			(layer "B.Fab")
			(hide yes)
			(effects
				(font
					(size 1 1)
					(thickness 0.15)
				)
				(justify mirror)
			)
		)
		(property "Manufacturer" "TDK"
			(at 0 0 180)
			(unlocked yes)
			(layer "B.Fab")
			(hide yes)
			(effects
				(font
					(size 1 1)
					(thickness 0.15)
				)
				(justify mirror)
			)
		)
		(property "Val" "3u3/2.5A"
			(at 0 0 180)
			(unlocked yes)
			(layer "B.Fab")
			(hide yes)
			(effects
				(font
					(size 1 1)
					(thickness 0.15)
				)
				(justify mirror)
			)
		)
		(property "Size" "2.5x2.0"
			(at 0 0 180)
			(unlocked yes)
			(layer "B.Fab")
			(hide yes)
			(effects
				(font
					(size 1 1)
					(thickness 0.15)
				)
				(justify mirror)
			)
		)
		(property "Author" "Antmicro"
			(at 0 0 180)
			(unlocked yes)
			(layer "B.Fab")
			(hide yes)
			(effects
				(font
					(size 1 1)
					(thickness 0.15)
				)
				(justify mirror)
			)
		)
		(property "License" "Apache-2.0"
			(at 0 0 180)
			(unlocked yes)
			(layer "B.Fab")
			(hide yes)
			(effects
				(font
					(size 1 1)
					(thickness 0.15)
				)
				(justify mirror)
			)
		)
		(sheetname "/DC-DC Converters/")
		(sheetfile "dc-dc_converters.kicad_sch")
		(attr smd)
		(fp_line
			(start 0.261 1.111)
			(end -0.264 1.111)
			(stroke
				(width 0.15)
				(type solid)
			)
			(layer "B.SilkS")
		)
		(fp_line
			(start 0.261 -1.11)
			(end -0.264 -1.11)
			(stroke
				(width 0.15)
				(type solid)
			)
			(layer "B.SilkS")
		)
		(fp_rect
			(start -1.95 1.25)
			(end 1.95 -1.25)
			(stroke
				(width 0.05)
				(type solid)
			)
			(fill no)
			(layer "B.CrtYd")
		)
		(fp_line
			(start 1.249 0.999)
			(end -1.05 0.999)
			(stroke
				(width 0.15)
				(type solid)
			)
			(layer "B.Fab")
		)
		(fp_line
			(start 1.249 -0.997)
			(end 1.249 0.999)
			(stroke
				(width 0.15)
				(type solid)
			)
			(layer "B.Fab")
		)
		(fp_line
			(start -1.05 0.999)
			(end -1.25 0.8)
			(stroke
				(width 0.15)
				(type solid)
			)
			(layer "B.Fab")
		)
		(fp_line
			(start -1.25 0.8)
			(end -1.25 -0.997)
			(stroke
				(width 0.15)
				(type solid)
			)
			(layer "B.Fab")
		)
		(fp_line
			(start -1.25 -0.997)
			(end 1.249 -0.997)
			(stroke
				(width 0.15)
				(type solid)
			)
			(layer "B.Fab")
		)
		(pad "1" smd roundrect
			(at -1.075 0 180)
			(size 1.25 2.2)
			(layers "B.Cu" "B.Mask" "B.Paste")
			(roundrect_rratio 0.1)
			(net 21 "Net-(U3-SW)")
			(pintype "passive")
		)
		(pad "2" smd roundrect
			(at 1.075 0 180)
			(size 1.25 2.2)
			(layers "B.Cu" "B.Mask" "B.Paste")
			(roundrect_rratio 0.1)
			(net 25 "+5V")
			(pintype "passive")
		)
	)
	(footprint "antmicro-footprints:C_0603_1608Metric"
		(layer "B.Cu")
		(at 83.9 82.8 -90)
		(descr "Capacitor SMD 0603")
		(tags "capacitor 0603")
		(property "Reference" "C22"
			(at -6.473 0.207 90)
			(layer "B.SilkS")
			(effects
				(font
					(size 0.7 0.7)
					(thickness 0.15)
				)
				(justify left bottom mirror)
			)
		)
		(property "Value" "C_10u_25V_0603"
			(at -1.42757 -1.770288 90)
			(layer "B.Fab")
			(effects
				(font
					(size 0.7 0.7)
					(thickness 0.15)
				)
				(justify left bottom mirror)
			)
		)
		(property "Datasheet" "https://product.tdk.com/en/search/capacitor/ceramic/mlcc/info?part_no=C1608X5R1E106M080AC"
			(at 0 0 270)
			(layer "F.Fab")
			(hide yes)
			(effects
				(font
					(size 1.27 1.27)
					(thickness 0.15)
				)
			)
		)
		(property "Description" "SMD Multilayer Ceramic Capacitor, 10 µF, 25 V, 0603 [1608 Metric], ± 20%, X5R, C"
			(at 0 0 270)
			(layer "F.Fab")
			(hide yes)
			(effects
				(font
					(size 1.27 1.27)
					(thickness 0.15)
				)
			)
		)
		(property "MPN" "C1608X5R1E106M080AC"
			(at 0 0 270)
			(unlocked yes)
			(layer "B.Fab")
			(hide yes)
			(effects
				(font
					(size 1 1)
					(thickness 0.15)
				)
				(justify mirror)
			)
		)
		(property "Manufacturer" "TDK"
			(at 0 0 270)
			(unlocked yes)
			(layer "B.Fab")
			(hide yes)
			(effects
				(font
					(size 1 1)
					(thickness 0.15)
				)
				(justify mirror)
			)
		)
		(property "License" "Apache-2.0"
			(at 0 0 270)
			(unlocked yes)
			(layer "B.Fab")
			(hide yes)
			(effects
				(font
					(size 1 1)
					(thickness 0.15)
				)
				(justify mirror)
			)
		)
		(property "Author" "Antmicro"
			(at 0 0 270)
			(unlocked yes)
			(layer "B.Fab")
			(hide yes)
			(effects
				(font
					(size 1 1)
					(thickness 0.15)
				)
				(justify mirror)
			)
		)
		(property "Val" "10u"
			(at 0 0 270)
			(unlocked yes)
			(layer "B.Fab")
			(hide yes)
			(effects
				(font
					(size 1 1)
					(thickness 0.15)
				)
				(justify mirror)
			)
		)
		(property "Voltage" "25V"
			(at 0 0 270)
			(unlocked yes)
			(layer "B.Fab")
			(hide yes)
			(effects
				(font
					(size 1 1)
					(thickness 0.15)
				)
				(justify mirror)
			)
		)
		(property "Dielectric" ""
			(at 0 0 270)
			(unlocked yes)
			(layer "B.Fab")
			(hide yes)
			(effects
				(font
					(size 1 1)
					(thickness 0.15)
				)
				(justify mirror)
			)
		)
		(sheetname "/DC-DC Converters/")
		(sheetfile "dc-dc_converters.kicad_sch")
		(attr smd)
		(fp_line
			(start 0.15 0.4)
			(end -0.15 0.4)
			(stroke
				(width 0.15)
				(type solid)
			)
			(layer "B.SilkS")
		)
		(fp_line
			(start 0.15 -0.4)
			(end -0.15 -0.4)
			(stroke
				(width 0.15)
				(type solid)
			)
			(layer "B.SilkS")
		)
		(fp_rect
			(start -1.25 0.65)
			(end 1.25 -0.65)
			(stroke
				(width 0.05)
				(type solid)
			)
			(fill no)
			(layer "B.CrtYd")
		)
		(fp_rect
			(start -0.8 0.4)
			(end 0.8 -0.4)
			(stroke
				(width 0.15)
				(type solid)
			)
			(fill no)
			(layer "B.Fab")
		)
		(pad "1" smd roundrect
			(at -0.7 0 270)
			(size 0.8 1)
			(layers "B.Cu" "B.Mask" "B.Paste")
			(roundrect_rratio 0.2)
			(net 2 "GND")
			(pintype "passive")
		)
		(pad "2" smd roundrect
			(at 0.7 0 270)
			(size 0.8 1)
			(layers "B.Cu" "B.Mask" "B.Paste")
			(roundrect_rratio 0.2)
			(net 5 "+12V")
			(pintype "passive")
		)
	)
	(footprint "antmicro-footprints:C_0805_2012Metric"
		(layer "B.Cu")
		(at 90.75 93.05 -90)
		(descr "Capacitor SMD 0805")
		(tags "capacitor SMD 0805")
		(property "Reference" "C29"
			(at -18.3 6.674 180)
			(layer "B.SilkS")
			(effects
				(font
					(size 0.7 0.7)
					(thickness 0.15)
				)
				(justify left bottom mirror)
			)
		)
		(property "Value" "C_22u_25V_0805"
			(at -2.055717 -1.963152 90)
			(layer "B.Fab")
			(effects
				(font
					(size 0.7 0.7)
					(thickness 0.15)
				)
				(justify left bottom mirror)
			)
		)
		(property "Datasheet" "https://product.samsungsem.com/mlcc/CL21A226MAYNNN.do"
			(at 0 0 270)
			(layer "F.Fab")
			(hide yes)
			(effects
				(font
					(size 1.27 1.27)
					(thickness 0.15)
				)
			)
		)
		(property "Description" "SMT Multilayer Ceramic Capacitor, 22uF, +/-20%, 25V, X5R, 0805 [2012 Metric]"
			(at 0 0 270)
			(layer "F.Fab")
			(hide yes)
			(effects
				(font
					(size 1.27 1.27)
					(thickness 0.15)
				)
			)
		)
		(property "MPN" "CL21A226MAYNNNE"
			(at 0 0 270)
			(unlocked yes)
			(layer "B.Fab")
			(hide yes)
			(effects
				(font
					(size 1 1)
					(thickness 0.15)
				)
				(justify mirror)
			)
		)
		(property "Manufacturer" "Samsung Electro-Mechanics"
			(at 0 0 270)
			(unlocked yes)
			(layer "B.Fab")
			(hide yes)
			(effects
				(font
					(size 1 1)
					(thickness 0.15)
				)
				(justify mirror)
			)
		)
		(property "License" "Apache-2.0"
			(at 0 0 270)
			(unlocked yes)
			(layer "B.Fab")
			(hide yes)
			(effects
				(font
					(size 1 1)
					(thickness 0.15)
				)
				(justify mirror)
			)
		)
		(property "Author" "Antmicro"
			(at 0 0 270)
			(unlocked yes)
			(layer "B.Fab")
			(hide yes)
			(effects
				(font
					(size 1 1)
					(thickness 0.15)
				)
				(justify mirror)
			)
		)
		(property "Val" "22u"
			(at 0 0 270)
			(unlocked yes)
			(layer "B.Fab")
			(hide yes)
			(effects
				(font
					(size 1 1)
					(thickness 0.15)
				)
				(justify mirror)
			)
		)
		(property "Voltage" "25V"
			(at 0 0 270)
			(unlocked yes)
			(layer "B.Fab")
			(hide yes)
			(effects
				(font
					(size 1 1)
					(thickness 0.15)
				)
				(justify mirror)
			)
		)
		(property "Dielectric" "X5R"
			(at 0 0 270)
			(unlocked yes)
			(layer "B.Fab")
			(hide yes)
			(effects
				(font
					(size 1 1)
					(thickness 0.15)
				)
				(justify mirror)
			)
		)
		(property "Public" "False"
			(at 0 0 270)
			(unlocked yes)
			(layer "B.Fab")
			(hide yes)
			(effects
				(font
					(size 1 1)
					(thickness 0.15)
				)
				(justify mirror)
			)
		)
		(sheetname "/DC-DC Converters/")
		(sheetfile "dc-dc_converters.kicad_sch")
		(attr smd)
		(fp_line
			(start 0.3 0.7)
			(end -0.3 0.7)
			(stroke
				(width 0.15)
				(type solid)
			)
			(layer "B.SilkS")
		)
		(fp_line
			(start 0.3 -0.7)
			(end -0.3 -0.7)
			(stroke
				(width 0.15)
				(type solid)
			)
			(layer "B.SilkS")
		)
		(fp_rect
			(start 1.95 0.9)
			(end -1.95 -0.9)
			(stroke
				(width 0.05)
				(type default)
			)
			(fill no)
			(layer "B.CrtYd")
		)
		(fp_rect
			(start -0.95 0.675)
			(end 0.95 -0.675)
			(stroke
				(width 0.15)
				(type solid)
			)
			(fill no)
			(layer "B.Fab")
		)
		(pad "1" smd roundrect
			(at -1.1 0 270)
			(size 1.2 1.3)
			(layers "B.Cu" "B.Mask" "B.Paste")
			(roundrect_rratio 0.25)
			(net 2 "GND")
			(pintype "passive")
		)
		(pad "2" smd roundrect
			(at 1.1 0 270)
			(size 1.2 1.3)
			(layers "B.Cu" "B.Mask" "B.Paste")
			(roundrect_rratio 0.25)
			(net 5 "+12V")
			(pintype "passive")
		)
	)
	(footprint "antmicro-footprints:C_1206_3216Metric"
		(layer "B.Cu")
		(at 91.2 97.85 90)
		(descr "Capacitor SMD 1206")
		(tags "capacitor SMD 1206")
		(property "Reference" "C34"
			(at 23.428 -4.838 180)
			(layer "B.SilkS")
			(effects
				(font
					(size 0.7 0.7)
					(thickness 0.15)
				)
				(justify left bottom mirror)
			)
		)
		(property "Value" "C_47u_25V_1206"
			(at 0 -2.101 90)
			(layer "B.Fab")
			(effects
				(font
					(size 0.7 0.7)
					(thickness 0.15)
				)
				(justify right bottom mirror)
			)
		)
		(property "Datasheet" "https://product.tdk.com/en/search/capacitor/ceramic/mlcc/info?part_no=C3216X5R1E476M160AC"
			(at 0 0 90)
			(layer "F.Fab")
			(hide yes)
			(effects
				(font
					(size 1.27 1.27)
					(thickness 0.15)
				)
			)
		)
		(property "Description" "SMD Multilayer Ceramic Capacitor, 47 µF, 25 V, 1206 [3216 Metric], ± 20%, X5R"
			(at 0 0 90)
			(layer "F.Fab")
			(hide yes)
			(effects
				(font
					(size 1.27 1.27)
					(thickness 0.15)
				)
			)
		)
		(property "MPN" "C3216X5R1E476M160AC"
			(at 0 0 90)
			(unlocked yes)
			(layer "B.Fab")
			(hide yes)
			(effects
				(font
					(size 1 1)
					(thickness 0.15)
				)
				(justify mirror)
			)
		)
		(property "Val" "47u"
			(at 0 0 90)
			(unlocked yes)
			(layer "B.Fab")
			(hide yes)
			(effects
				(font
					(size 1 1)
					(thickness 0.15)
				)
				(justify mirror)
			)
		)
		(property "Voltage" "25V"
			(at 0 0 90)
			(unlocked yes)
			(layer "B.Fab")
			(hide yes)
			(effects
				(font
					(size 1 1)
					(thickness 0.15)
				)
				(justify mirror)
			)
		)
		(property "Author" "Antmicro"
			(at 0 0 90)
			(unlocked yes)
			(layer "B.Fab")
			(hide yes)
			(effects
				(font
					(size 1 1)
					(thickness 0.15)
				)
				(justify mirror)
			)
		)
		(property "License" "Apache-2.0"
			(at 0 0 90)
			(unlocked yes)
			(layer "B.Fab")
			(hide yes)
			(effects
				(font
					(size 1 1)
					(thickness 0.15)
				)
				(justify mirror)
			)
		)
		(property "Manufacturer" "TDK"
			(at 0 0 90)
			(unlocked yes)
			(layer "B.Fab")
			(hide yes)
			(effects
				(font
					(size 1 1)
					(thickness 0.15)
				)
				(justify mirror)
			)
		)
		(property "Dielectric" "X5R"
			(at 0 0 90)
			(unlocked yes)
			(layer "B.Fab")
			(hide yes)
			(effects
				(font
					(size 1 1)
					(thickness 0.15)
				)
				(justify mirror)
			)
		)
		(property "Public" "False"
			(at 0 0 90)
			(unlocked yes)
			(layer "B.Fab")
			(hide yes)
			(effects
				(font
					(size 1 1)
					(thickness 0.15)
				)
				(justify mirror)
			)
		)
		(sheetname "/DC-DC Converters/")
		(sheetfile "dc-dc_converters.kicad_sch")
		(attr smd)
		(fp_line
			(start -0.8 -0.901)
			(end 0.8 -0.901)
			(stroke
				(width 0.15)
				(type solid)
			)
			(layer "B.SilkS")
		)
		(fp_line
			(start -0.8 0.899)
			(end 0.8 0.899)
			(stroke
				(width 0.15)
				(type solid)
			)
			(layer "B.SilkS")
		)
		(fp_rect
			(start -2.325 1.15)
			(end 2.325 -1.15)
			(stroke
				(width 0.05)
				(type default)
			)
			(fill no)
			(layer "B.CrtYd")
		)
		(fp_rect
			(start -1.6 0.799)
			(end 1.6 -0.801)
			(stroke
				(width 0.15)
				(type solid)
			)
			(fill no)
			(layer "B.Fab")
		)
		(pad "1" smd roundrect
			(at -1.5 -0.001 90)
			(size 1.15 1.8)
			(layers "B.Cu" "B.Mask" "B.Paste")
			(roundrect_rratio 0.25)
			(net 2 "GND")
			(pintype "passive")
		)
		(pad "2" smd roundrect
			(at 1.5 -0.001 90)
			(size 1.15 1.8)
			(layers "B.Cu" "B.Mask" "B.Paste")
			(roundrect_rratio 0.25)
			(net 5 "+12V")
			(pintype "passive")
		)
	)
	(footprint "antmicro-footprints:WSON-6-1EP_2x2mm_P0.65mm"
		(layer "B.Cu")
		(at 91.6 66.8 180)
		(property "Reference" "U5"
			(at 1.324 0.75 90)
			(layer "B.SilkS")
			(effects
				(font
					(size 0.7 0.7)
					(thickness 0.15)
				)
				(justify left bottom mirror)
			)
		)
		(property "Value" "TVS2200DRVR"
			(at 0 -2.2 0)
			(layer "B.Fab")
			(effects
				(font
					(size 0.7 0.7)
					(thickness 0.15)
				)
				(justify left bottom mirror)
			)
		)
		(property "Datasheet" "https://www.ti.com/lit/ds/symlink/tvs2200.pdf?ts=1712230685180&ref_url=https%253A%252F%252Fwww.ti.com%252Fproduct%252FTVS2200"
			(at 0 0 180)
			(layer "F.Fab")
			(hide yes)
			(effects
				(font
					(size 1.27 1.27)
					(thickness 0.15)
				)
			)
		)
		(property "Description" "ESD Protection Device, 1 kV, WSON-6, 22 V, 105 pF"
			(at 0 0 180)
			(layer "F.Fab")
			(hide yes)
			(effects
				(font
					(size 1.27 1.27)
					(thickness 0.15)
				)
			)
		)
		(property "MPN" "TVS2200DRVR"
			(at 0 0 180)
			(unlocked yes)
			(layer "B.Fab")
			(hide yes)
			(effects
				(font
					(size 1 1)
					(thickness 0.15)
				)
				(justify mirror)
			)
		)
		(property "Manufacturer" "Texas Instruments"
			(at 0 0 180)
			(unlocked yes)
			(layer "B.Fab")
			(hide yes)
			(effects
				(font
					(size 1 1)
					(thickness 0.15)
				)
				(justify mirror)
			)
		)
		(property "License" "Apache-2.0"
			(at 0 0 180)
			(unlocked yes)
			(layer "B.Fab")
			(hide yes)
			(effects
				(font
					(size 1 1)
					(thickness 0.15)
				)
				(justify mirror)
			)
		)
		(property "Author" "Antmicro"
			(at 0 0 180)
			(unlocked yes)
			(layer "B.Fab")
			(hide yes)
			(effects
				(font
					(size 1 1)
					(thickness 0.15)
				)
				(justify mirror)
			)
		)
		(sheetname "/USB PD/")
		(sheetfile "usb_pd.kicad_sch")
		(attr smd)
		(fp_line
			(start 1 -1)
			(end -1 -1)
			(stroke
				(width 0.12)
				(type solid)
			)
			(layer "B.SilkS")
		)
		(fp_line
			(start -1.05 1)
			(end 1 1)
			(stroke
				(width 0.12)
				(type solid)
			)
			(layer "B.SilkS")
		)
		(fp_circle
			(center -1.275 1.075)
			(end -1.224 1.075)
			(stroke
				(width 0.15)
				(type solid)
			)
			(fill yes)
			(layer "B.SilkS")
		)
		(fp_rect
			(start -1.45 1.25)
			(end 1.45 -1.25)
			(stroke
				(width 0.05)
				(type solid)
			)
			(fill no)
			(layer "B.CrtYd")
		)
		(pad "1" smd roundrect
			(at -0.975 0.652 180)
			(size 0.45 0.4)
			(layers "B.Cu" "B.Mask" "B.Paste")
			(roundrect_rratio 0.25)
			(net 2 "GND")
			(pinfunction "GND")
			(pintype "passive")
		)
		(pad "2" smd roundrect
			(at -0.975 0 180)
			(size 0.45 0.4)
			(layers "B.Cu" "B.Mask" "B.Paste")
			(roundrect_rratio 0.25)
			(net 2 "GND")
			(pinfunction "GND")
			(pintype "passive")
		)
		(pad "3" smd roundrect
			(at -0.975 -0.65 180)
			(size 0.45 0.4)
			(layers "B.Cu" "B.Mask" "B.Paste")
			(roundrect_rratio 0.25)
			(net 2 "GND")
			(pinfunction "GND")
			(pintype "passive")
		)
		(pad "4" smd roundrect
			(at 0.973 -0.65 180)
			(size 0.45 0.4)
			(layers "B.Cu" "B.Mask" "B.Paste")
			(roundrect_rratio 0.25)
			(net 6 "VBUS")
			(pinfunction "IN")
			(pintype "passive")
		)
		(pad "5" smd roundrect
			(at 0.973 0 180)
			(size 0.45 0.4)
			(layers "B.Cu" "B.Mask" "B.Paste")
			(roundrect_rratio 0.25)
			(net 6 "VBUS")
			(pinfunction "IN")
			(pintype "passive")
		)
		(pad "6" smd roundrect
			(at 0.973 0.652 180)
			(size 0.45 0.4)
			(layers "B.Cu" "B.Mask" "B.Paste")
			(roundrect_rratio 0.25)
			(net 6 "VBUS")
			(pinfunction "IN")
			(pintype "passive")
		)
		(pad "7" smd roundrect
			(at 0 0 180)
			(size 1.12 1.72)
			(layers "B.Cu" "B.Mask" "B.Paste")
			(roundrect_rratio 0.1)
			(net 2 "GND")
			(pinfunction "GND")
			(pintype "passive")
		)
	)
	(footprint "antmicro-footprints:C_0603_1608Metric"
		(layer "B.Cu")
		(at 85.726 90.75 180)
		(descr "Capacitor SMD 0603")
		(tags "capacitor 0603")
		(property "Reference" "C21"
			(at -1.474 -1.65 180)
			(layer "B.SilkS")
			(effects
				(font
					(size 0.7 0.7)
					(thickness 0.15)
				)
				(justify left bottom mirror)
			)
		)
		(property "Value" "C_10u_25V_0603"
			(at -1.42757 -1.770288 0)
			(layer "B.Fab")
			(effects
				(font
					(size 0.7 0.7)
					(thickness 0.15)
				)
				(justify left bottom mirror)
			)
		)
		(property "Datasheet" "https://product.tdk.com/en/search/capacitor/ceramic/mlcc/info?part_no=C1608X5R1E106M080AC"
			(at 0 0 180)
			(layer "F.Fab")
			(hide yes)
			(effects
				(font
					(size 1.27 1.27)
					(thickness 0.15)
				)
			)
		)
		(property "Description" "SMD Multilayer Ceramic Capacitor, 10 µF, 25 V, 0603 [1608 Metric], ± 20%, X5R, C"
			(at 0 0 180)
			(layer "F.Fab")
			(hide yes)
			(effects
				(font
					(size 1.27 1.27)
					(thickness 0.15)
				)
			)
		)
		(property "MPN" "C1608X5R1E106M080AC"
			(at 0 0 180)
			(unlocked yes)
			(layer "B.Fab")
			(hide yes)
			(effects
				(font
					(size 1 1)
					(thickness 0.15)
				)
				(justify mirror)
			)
		)
		(property "Manufacturer" "TDK"
			(at 0 0 180)
			(unlocked yes)
			(layer "B.Fab")
			(hide yes)
			(effects
				(font
					(size 1 1)
					(thickness 0.15)
				)
				(justify mirror)
			)
		)
		(property "License" "Apache-2.0"
			(at 0 0 180)
			(unlocked yes)
			(layer "B.Fab")
			(hide yes)
			(effects
				(font
					(size 1 1)
					(thickness 0.15)
				)
				(justify mirror)
			)
		)
		(property "Author" "Antmicro"
			(at 0 0 180)
			(unlocked yes)
			(layer "B.Fab")
			(hide yes)
			(effects
				(font
					(size 1 1)
					(thickness 0.15)
				)
				(justify mirror)
			)
		)
		(property "Val" "10u"
			(at 0 0 180)
			(unlocked yes)
			(layer "B.Fab")
			(hide yes)
			(effects
				(font
					(size 1 1)
					(thickness 0.15)
				)
				(justify mirror)
			)
		)
		(property "Voltage" "25V"
			(at 0 0 180)
			(unlocked yes)
			(layer "B.Fab")
			(hide yes)
			(effects
				(font
					(size 1 1)
					(thickness 0.15)
				)
				(justify mirror)
			)
		)
		(property "Dielectric" ""
			(at 0 0 180)
			(unlocked yes)
			(layer "B.Fab")
			(hide yes)
			(effects
				(font
					(size 1 1)
					(thickness 0.15)
				)
				(justify mirror)
			)
		)
		(sheetname "/DC-DC Converters/")
		(sheetfile "dc-dc_converters.kicad_sch")
		(attr smd)
		(fp_line
			(start 0.15 0.4)
			(end -0.15 0.4)
			(stroke
				(width 0.15)
				(type solid)
			)
			(layer "B.SilkS")
		)
		(fp_line
			(start 0.15 -0.4)
			(end -0.15 -0.4)
			(stroke
				(width 0.15)
				(type solid)
			)
			(layer "B.SilkS")
		)
		(fp_rect
			(start -1.25 0.65)
			(end 1.25 -0.65)
			(stroke
				(width 0.05)
				(type solid)
			)
			(fill no)
			(layer "B.CrtYd")
		)
		(fp_rect
			(start -0.8 0.4)
			(end 0.8 -0.4)
			(stroke
				(width 0.15)
				(type solid)
			)
			(fill no)
			(layer "B.Fab")
		)
		(pad "1" smd roundrect
			(at -0.7 0 180)
			(size 0.8 1)
			(layers "B.Cu" "B.Mask" "B.Paste")
			(roundrect_rratio 0.2)
			(net 2 "GND")
			(pintype "passive")
		)
		(pad "2" smd roundrect
			(at 0.7 0 180)
			(size 0.8 1)
			(layers "B.Cu" "B.Mask" "B.Paste")
			(roundrect_rratio 0.2)
			(net 5 "+12V")
			(pintype "passive")
		)
	)
	(footprint "antmicro-footprints:C_0402_1005Metric"
		(layer "B.Cu")
		(at 96.4 89.05 -90)
		(descr "Capacitor SMD 0402")
		(tags "capacitor SMD 0402")
		(property "Reference" "C42"
			(at -1.1 0.6 90)
			(layer "B.SilkS")
			(effects
				(font
					(size 0.7 0.7)
					(thickness 0.15)
				)
				(justify left bottom mirror)
			)
		)
		(property "Value" "C_1u_25V_0402"
			(at -1.022927 -2.155213 90)
			(layer "B.Fab")
			(effects
				(font
					(size 0.7 0.7)
					(thickness 0.15)
				)
				(justify left bottom mirror)
			)
		)
		(property "Datasheet" "https://www.murata.com/products/productdetail?partno=GRM155R61E105KE11%23"
			(at 0 0 270)
			(layer "F.Fab")
			(hide yes)
			(effects
				(font
					(size 1.27 1.27)
					(thickness 0.15)
				)
			)
		)
		(property "Description" "SMD Multilayer Ceramic Capacitor, 1 µF, 25 V, 0402 [1005 Metric], ± 10%, X5R, GRM Series"
			(at 0 0 270)
			(layer "F.Fab")
			(hide yes)
			(effects
				(font
					(size 1.27 1.27)
					(thickness 0.15)
				)
			)
		)
		(property "MPN" "GRM155R61E105KE11J"
			(at 0 0 270)
			(unlocked yes)
			(layer "B.Fab")
			(hide yes)
			(effects
				(font
					(size 1 1)
					(thickness 0.15)
				)
				(justify mirror)
			)
		)
		(property "Manufacturer" "Murata"
			(at 0 0 270)
			(unlocked yes)
			(layer "B.Fab")
			(hide yes)
			(effects
				(font
					(size 1 1)
					(thickness 0.15)
				)
				(justify mirror)
			)
		)
		(property "License" "Apache-2.0"
			(at 0 0 270)
			(unlocked yes)
			(layer "B.Fab")
			(hide yes)
			(effects
				(font
					(size 1 1)
					(thickness 0.15)
				)
				(justify mirror)
			)
		)
		(property "Author" "Antmicro"
			(at 0 0 270)
			(unlocked yes)
			(layer "B.Fab")
			(hide yes)
			(effects
				(font
					(size 1 1)
					(thickness 0.15)
				)
				(justify mirror)
			)
		)
		(property "Val" "1u"
			(at 0 0 270)
			(unlocked yes)
			(layer "B.Fab")
			(hide yes)
			(effects
				(font
					(size 1 1)
					(thickness 0.15)
				)
				(justify mirror)
			)
		)
		(property "Voltage" "25V"
			(at 0 0 270)
			(unlocked yes)
			(layer "B.Fab")
			(hide yes)
			(effects
				(font
					(size 1 1)
					(thickness 0.15)
				)
				(justify mirror)
			)
		)
		(property "Dielectric" "X5R"
			(at 0 0 270)
			(unlocked yes)
			(layer "B.Fab")
			(hide yes)
			(effects
				(font
					(size 1 1)
					(thickness 0.15)
				)
				(justify mirror)
			)
		)
		(sheetname "/DC-DC Converters/")
		(sheetfile "dc-dc_converters.kicad_sch")
		(attr smd)
		(fp_rect
			(start -0.925 0.47)
			(end 0.925 -0.47)
			(stroke
				(width 0.05)
				(type default)
			)
			(fill no)
			(layer "B.CrtYd")
		)
		(fp_line
			(start -0.494 0.25)
			(end -0.494 -0.248)
			(stroke
				(width 0.15)
				(type solid)
			)
			(layer "B.Fab")
		)
		(fp_line
			(start 0.504 0.25)
			(end -0.494 0.25)
			(stroke
				(width 0.15)
				(type solid)
			)
			(layer "B.Fab")
		)
		(fp_line
			(start -0.494 -0.248)
			(end 0.504 -0.248)
			(stroke
				(width 0.15)
				(type solid)
			)
			(layer "B.Fab")
		)
		(fp_line
			(start 0.504 -0.248)
			(end 0.504 0.25)
			(stroke
				(width 0.15)
				(type solid)
			)
			(layer "B.Fab")
		)
		(pad "1" smd roundrect
			(at -0.48 0 270)
			(size 0.59 0.64)
			(layers "B.Cu" "B.Mask" "B.Paste")
			(roundrect_rratio 0.25)
			(net 2 "GND")
			(pintype "passive")
		)
		(pad "2" smd roundrect
			(at 0.48 0 270)
			(size 0.59 0.64)
			(layers "B.Cu" "B.Mask" "B.Paste")
			(roundrect_rratio 0.25)
			(net 25 "+5V")
			(pintype "passive")
		)
	)
	(footprint "antmicro-footprints:C_0805_2012Metric"
		(layer "B.Cu")
		(at 99.75 98.2 90)
		(descr "Capacitor SMD 0805")
		(tags "capacitor SMD 0805")
		(property "Reference" "C36"
			(at 1.807 -0.69 180)
			(layer "B.SilkS")
			(effects
				(font
					(size 0.7 0.7)
					(thickness 0.15)
				)
				(justify right bottom mirror)
			)
		)
		(property "Value" "C_22u_25V_0805"
			(at -2.055717 -1.963152 90)
			(layer "B.Fab")
			(effects
				(font
					(size 0.7 0.7)
					(thickness 0.15)
				)
				(justify right bottom mirror)
			)
		)
		(property "Datasheet" "https://product.samsungsem.com/mlcc/CL21A226MAYNNN.do"
			(at 0 0 90)
			(layer "F.Fab")
			(hide yes)
			(effects
				(font
					(size 1.27 1.27)
					(thickness 0.15)
				)
			)
		)
		(property "Description" "SMT Multilayer Ceramic Capacitor, 22uF, +/-20%, 25V, X5R, 0805 [2012 Metric]"
			(at 0 0 90)
			(layer "F.Fab")
			(hide yes)
			(effects
				(font
					(size 1.27 1.27)
					(thickness 0.15)
				)
			)
		)
		(property "MPN" "CL21A226MAYNNNE"
			(at 0 0 90)
			(unlocked yes)
			(layer "B.Fab")
			(hide yes)
			(effects
				(font
					(size 1 1)
					(thickness 0.15)
				)
				(justify mirror)
			)
		)
		(property "Manufacturer" "Samsung Electro-Mechanics"
			(at 0 0 90)
			(unlocked yes)
			(layer "B.Fab")
			(hide yes)
			(effects
				(font
					(size 1 1)
					(thickness 0.15)
				)
				(justify mirror)
			)
		)
		(property "License" "Apache-2.0"
			(at 0 0 90)
			(unlocked yes)
			(layer "B.Fab")
			(hide yes)
			(effects
				(font
					(size 1 1)
					(thickness 0.15)
				)
				(justify mirror)
			)
		)
		(property "Author" "Antmicro"
			(at 0 0 90)
			(unlocked yes)
			(layer "B.Fab")
			(hide yes)
			(effects
				(font
					(size 1 1)
					(thickness 0.15)
				)
				(justify mirror)
			)
		)
		(property "Val" "22u"
			(at 0 0 90)
			(unlocked yes)
			(layer "B.Fab")
			(hide yes)
			(effects
				(font
					(size 1 1)
					(thickness 0.15)
				)
				(justify mirror)
			)
		)
		(property "Voltage" "25V"
			(at 0 0 90)
			(unlocked yes)
			(layer "B.Fab")
			(hide yes)
			(effects
				(font
					(size 1 1)
					(thickness 0.15)
				)
				(justify mirror)
			)
		)
		(property "Dielectric" "X5R"
			(at 0 0 90)
			(unlocked yes)
			(layer "B.Fab")
			(hide yes)
			(effects
				(font
					(size 1 1)
					(thickness 0.15)
				)
				(justify mirror)
			)
		)
		(property "Public" "False"
			(at 0 0 90)
			(unlocked yes)
			(layer "B.Fab")
			(hide yes)
			(effects
				(font
					(size 1 1)
					(thickness 0.15)
				)
				(justify mirror)
			)
		)
		(sheetname "/DC-DC Converters/")
		(sheetfile "dc-dc_converters.kicad_sch")
		(attr smd)
		(fp_line
			(start 0.3 -0.7)
			(end -0.3 -0.7)
			(stroke
				(width 0.15)
				(type solid)
			)
			(layer "B.SilkS")
		)
		(fp_line
			(start 0.3 0.7)
			(end -0.3 0.7)
			(stroke
				(width 0.15)
				(type solid)
			)
			(layer "B.SilkS")
		)
		(fp_rect
			(start 1.95 0.9)
			(end -1.95 -0.9)
			(stroke
				(width 0.05)
				(type default)
			)
			(fill no)
			(layer "B.CrtYd")
		)
		(fp_rect
			(start -0.95 0.675)
			(end 0.95 -0.675)
			(stroke
				(width 0.15)
				(type solid)
			)
			(fill no)
			(layer "B.Fab")
		)
		(pad "1" smd roundrect
			(at -1.1 0 90)
			(size 1.2 1.3)
			(layers "B.Cu" "B.Mask" "B.Paste")
			(roundrect_rratio 0.25)
			(net 2 "GND")
			(pintype "passive")
		)
		(pad "2" smd roundrect
			(at 1.1 0 90)
			(size 1.2 1.3)
			(layers "B.Cu" "B.Mask" "B.Paste")
			(roundrect_rratio 0.25)
			(net 5 "+12V")
			(pintype "passive")
		)
	)
	(footprint "antmicro-footprints:C_0402_1005Metric"
		(layer "B.Cu")
		(at 82.476 92.35 -90)
		(descr "Capacitor SMD 0402")
		(tags "capacitor SMD 0402")
		(property "Reference" "C40"
			(at 0.5 -2.6 180)
			(layer "B.SilkS")
			(effects
				(font
					(size 0.7 0.7)
					(thickness 0.15)
				)
				(justify left bottom mirror)
			)
		)
		(property "Value" "C_1u_25V_0402"
			(at -1.022927 -2.155213 90)
			(layer "B.Fab")
			(effects
				(font
					(size 0.7 0.7)
					(thickness 0.15)
				)
				(justify left bottom mirror)
			)
		)
		(property "Datasheet" "https://www.murata.com/products/productdetail?partno=GRM155R61E105KE11%23"
			(at 0 0 270)
			(layer "F.Fab")
			(hide yes)
			(effects
				(font
					(size 1.27 1.27)
					(thickness 0.15)
				)
			)
		)
		(property "Description" "SMD Multilayer Ceramic Capacitor, 1 µF, 25 V, 0402 [1005 Metric], ± 10%, X5R, GRM Series"
			(at 0 0 270)
			(layer "F.Fab")
			(hide yes)
			(effects
				(font
					(size 1.27 1.27)
					(thickness 0.15)
				)
			)
		)
		(property "MPN" "GRM155R61E105KE11J"
			(at 0 0 270)
			(unlocked yes)
			(layer "B.Fab")
			(hide yes)
			(effects
				(font
					(size 1 1)
					(thickness 0.15)
				)
				(justify mirror)
			)
		)
		(property "Manufacturer" "Murata"
			(at 0 0 270)
			(unlocked yes)
			(layer "B.Fab")
			(hide yes)
			(effects
				(font
					(size 1 1)
					(thickness 0.15)
				)
				(justify mirror)
			)
		)
		(property "License" "Apache-2.0"
			(at 0 0 270)
			(unlocked yes)
			(layer "B.Fab")
			(hide yes)
			(effects
				(font
					(size 1 1)
					(thickness 0.15)
				)
				(justify mirror)
			)
		)
		(property "Author" "Antmicro"
			(at 0 0 270)
			(unlocked yes)
			(layer "B.Fab")
			(hide yes)
			(effects
				(font
					(size 1 1)
					(thickness 0.15)
				)
				(justify mirror)
			)
		)
		(property "Val" "1u"
			(at 0 0 270)
			(unlocked yes)
			(layer "B.Fab")
			(hide yes)
			(effects
				(font
					(size 1 1)
					(thickness 0.15)
				)
				(justify mirror)
			)
		)
		(property "Voltage" "25V"
			(at 0 0 270)
			(unlocked yes)
			(layer "B.Fab")
			(hide yes)
			(effects
				(font
					(size 1 1)
					(thickness 0.15)
				)
				(justify mirror)
			)
		)
		(property "Dielectric" "X5R"
			(at 0 0 270)
			(unlocked yes)
			(layer "B.Fab")
			(hide yes)
			(effects
				(font
					(size 1 1)
					(thickness 0.15)
				)
				(justify mirror)
			)
		)
		(sheetname "/DC-DC Converters/")
		(sheetfile "dc-dc_converters.kicad_sch")
		(attr smd)
		(fp_rect
			(start -0.925 0.47)
			(end 0.925 -0.47)
			(stroke
				(width 0.05)
				(type default)
			)
			(fill no)
			(layer "B.CrtYd")
		)
		(fp_line
			(start -0.494 0.25)
			(end -0.494 -0.248)
			(stroke
				(width 0.15)
				(type solid)
			)
			(layer "B.Fab")
		)
		(fp_line
			(start 0.504 0.25)
			(end -0.494 0.25)
			(stroke
				(width 0.15)
				(type solid)
			)
			(layer "B.Fab")
		)
		(fp_line
			(start -0.494 -0.248)
			(end 0.504 -0.248)
			(stroke
				(width 0.15)
				(type solid)
			)
			(layer "B.Fab")
		)
		(fp_line
			(start 0.504 -0.248)
			(end 0.504 0.25)
			(stroke
				(width 0.15)
				(type solid)
			)
			(layer "B.Fab")
		)
		(pad "1" smd roundrect
			(at -0.48 0 270)
			(size 0.59 0.64)
			(layers "B.Cu" "B.Mask" "B.Paste")
			(roundrect_rratio 0.25)
			(net 2 "GND")
			(pintype "passive")
		)
		(pad "2" smd roundrect
			(at 0.48 0 270)
			(size 0.59 0.64)
			(layers "B.Cu" "B.Mask" "B.Paste")
			(roundrect_rratio 0.25)
			(net 26 "Net-(D5-C)")
			(pintype "passive")
		)
	)
	(footprint "antmicro-footprints:USB-C_Receptacle_GCT_USB4105-GF-A"
		(locked yes)
		(layer "B.Cu")
		(at 87.929 61.074)
		(property "Reference" "J1"
			(at -5.252 3.95 90)
			(layer "B.SilkS")
			(effects
				(font
					(size 0.7 0.7)
					(thickness 0.15)
				)
				(justify right bottom mirror)
			)
		)
		(property "Value" "USB-C_GCT_USB4105-GF-A"
			(at 0 -5 0)
			(layer "B.Fab")
			(effects
				(font
					(size 0.7 0.7)
					(thickness 0.15)
				)
				(justify right bottom mirror)
			)
		)
		(property "Datasheet" "https://gct.co/files/drawings/usb4105.pdf"
			(at 0 0 0)
			(layer "F.Fab")
			(hide yes)
			(effects
				(font
					(size 1.27 1.27)
					(thickness 0.15)
				)
			)
		)
		(property "Description" "USB-C (USB TYPE-C) USB 2.0 Receptacle Connector 24 (16+8 Dummy) Position Surface Mount, Right Angle"
			(at 0 0 0)
			(layer "F.Fab")
			(hide yes)
			(effects
				(font
					(size 1.27 1.27)
					(thickness 0.15)
				)
			)
		)
		(property "Manufacturer" "GCT"
			(at 0 0 0)
			(unlocked yes)
			(layer "B.Fab")
			(hide yes)
			(effects
				(font
					(size 1 1)
					(thickness 0.15)
				)
				(justify mirror)
			)
		)
		(property "MPN" "USB4105-GF-A"
			(at 0 0 0)
			(unlocked yes)
			(layer "B.Fab")
			(hide yes)
			(effects
				(font
					(size 1 1)
					(thickness 0.15)
				)
				(justify mirror)
			)
		)
		(property "Author" "Antmicro"
			(at 0 0 0)
			(unlocked yes)
			(layer "B.Fab")
			(hide yes)
			(effects
				(font
					(size 1 1)
					(thickness 0.15)
				)
				(justify mirror)
			)
		)
		(property "License" "Apache-2.0"
			(at 0 0 0)
			(unlocked yes)
			(layer "B.Fab")
			(hide yes)
			(effects
				(font
					(size 1 1)
					(thickness 0.15)
				)
				(justify mirror)
			)
		)
		(sheetname "/USB PD/")
		(sheetfile "usb_pd.kicad_sch")
		(attr smd)
		(fp_line
			(start -4.79 -3.854)
			(end -4.79 -2.575)
			(stroke
				(width 0.15)
				(type solid)
			)
			(layer "B.SilkS")
		)
		(fp_line
			(start -4.79 0.145)
			(end -4.79 1.395)
			(stroke
				(width 0.15)
				(type solid)
			)
			(layer "B.SilkS")
		)
		(fp_line
			(start 4.788 -3.854)
			(end -4.79 -3.854)
			(stroke
				(width 0.15)
				(type solid)
			)
			(layer "B.SilkS")
		)
		(fp_line
			(start 4.788 -2.575)
			(end 4.788 -3.854)
			(stroke
				(width 0.15)
				(type solid)
			)
			(layer "B.SilkS")
		)
		(fp_line
			(start 4.788 0.145)
			(end 4.788 1.395)
			(stroke
				(width 0.15)
				(type solid)
			)
			(layer "B.SilkS")
		)
		(fp_circle
			(center -3.8 4.27071)
			(end -3.75 4.22071)
			(stroke
				(width 0.15)
				(type solid)
			)
			(fill yes)
			(layer "B.SilkS")
		)
		(fp_rect
			(start -5.1 4.4)
			(end 5.1 -3.9)
			(stroke
				(width 0.05)
				(type solid)
			)
			(fill no)
			(layer "B.CrtYd")
		)
		(fp_line
			(start -4.79 -3.854)
			(end 4.788 -3.854)
			(stroke
				(width 0.15)
				(type solid)
			)
			(layer "B.Fab")
		)
		(fp_line
			(start -4.79 3.676)
			(end -4.79 -3.854)
			(stroke
				(width 0.15)
				(type solid)
			)
			(layer "B.Fab")
		)
		(fp_line
			(start 4.788 -3.854)
			(end -4.702 -3.854)
			(stroke
				(width 0.15)
				(type solid)
			)
			(layer "B.Fab")
		)
		(fp_line
			(start 4.788 -3.854)
			(end 4.788 3.676)
			(stroke
				(width 0.15)
				(type solid)
			)
			(layer "B.Fab")
		)
		(fp_line
			(start 4.788 3.676)
			(end -4.79 3.676)
			(stroke
				(width 0.15)
				(type solid)
			)
			(layer "B.Fab")
		)
		(pad "" np_thru_hole circle
			(at -2.891 2.426)
			(size 0.65 0.65)
			(drill 0.65)
			(layers "*.Cu" "*.Mask")
		)
		(pad "" np_thru_hole circle
			(at 2.89 2.426)
			(size 0.65 0.65)
			(drill 0.65)
			(layers "*.Cu" "*.Mask")
		)
		(pad "A1" smd roundrect
			(at -3.202 3.5)
			(size 0.6 1.15)
			(layers "B.Cu" "B.Mask" "B.Paste")
			(roundrect_rratio 0.25)
			(net 2 "GND")
			(pinfunction "GND")
			(pintype "power_in")
		)
		(pad "A4" smd roundrect
			(at -2.4 3.5)
			(size 0.6 1.15)
			(layers "B.Cu" "B.Mask" "B.Paste")
			(roundrect_rratio 0.25)
			(net 6 "VBUS")
			(pinfunction "VBUS")
			(pintype "power_in")
		)
		(pad "A5" smd roundrect
			(at -1.25 3.5)
			(size 0.3 1.15)
			(layers "B.Cu" "B.Mask" "B.Paste")
			(roundrect_rratio 0.25)
			(net 29 "/USB PD/CC1")
			(pinfunction "CC_{1}")
			(pintype "bidirectional")
		)
		(pad "A6" smd roundrect
			(at -0.25 3.5)
			(size 0.3 1.15)
			(layers "B.Cu" "B.Mask" "B.Paste")
			(roundrect_rratio 0.25)
			(net 30 "unconnected-(J1-D_{A}+-PadA6)")
			(pinfunction "D_{A}+")
			(pintype "bidirectional+no_connect")
		)
		(pad "A7" smd roundrect
			(at 0.248 3.5)
			(size 0.3 1.15)
			(layers "B.Cu" "B.Mask" "B.Paste")
			(roundrect_rratio 0.25)
			(net 31 "unconnected-(J1-D_{A}--PadA7)")
			(pinfunction "D_{A}-")
			(pintype "bidirectional+no_connect")
		)
		(pad "A8" smd roundrect
			(at 1.249 3.5)
			(size 0.3 1.15)
			(layers "B.Cu" "B.Mask" "B.Paste")
			(roundrect_rratio 0.25)
			(net 32 "unconnected-(J1-SBU_{1}-PadA8)")
			(pinfunction "SBU_{1}")
			(pintype "bidirectional+no_connect")
		)
		(pad "A9" smd roundrect
			(at 2.398 3.5)
			(size 0.6 1.15)
			(layers "B.Cu" "B.Mask" "B.Paste")
			(roundrect_rratio 0.25)
			(net 6 "VBUS")
			(pinfunction "VBUS")
			(pintype "passive")
		)
		(pad "A12" smd roundrect
			(at 3.2 3.5)
			(size 0.6 1.15)
			(layers "B.Cu" "B.Mask" "B.Paste")
			(roundrect_rratio 0.25)
			(net 2 "GND")
			(pinfunction "GND")
			(pintype "passive")
		)
		(pad "B1" smd roundrect
			(at 3.2 3.5)
			(size 0.6 1.15)
			(layers "B.Cu" "B.Mask" "B.Paste")
			(roundrect_rratio 0.25)
			(net 2 "GND")
			(pinfunction "GND")
			(pintype "passive")
		)
		(pad "B4" smd roundrect
			(at 2.398 3.5)
			(size 0.6 1.15)
			(layers "B.Cu" "B.Mask" "B.Paste")
			(roundrect_rratio 0.25)
			(net 6 "VBUS")
			(pinfunction "VBUS")
			(pintype "passive")
		)
		(pad "B5" smd roundrect
			(at 1.749 3.5)
			(size 0.3 1.15)
			(layers "B.Cu" "B.Mask" "B.Paste")
			(roundrect_rratio 0.25)
			(net 33 "/USB PD/CC2")
			(pinfunction "CC_{2}")
			(pintype "bidirectional")
		)
		(pad "B6" smd roundrect
			(at 0.748 3.5)
			(size 0.3 1.15)
			(layers "B.Cu" "B.Mask" "B.Paste")
			(roundrect_rratio 0.25)
			(net 34 "unconnected-(J1-D_{B}+-PadB6)")
			(pinfunction "D_{B}+")
			(pintype "bidirectional+no_connect")
		)
		(pad "B7" smd roundrect
			(at -0.75 3.5)
			(size 0.3 1.15)
			(layers "B.Cu" "B.Mask" "B.Paste")
			(roundrect_rratio 0.25)
			(net 35 "unconnected-(J1-D_{B}--PadB7)")
			(pinfunction "D_{B}-")
			(pintype "bidirectional+no_connect")
		)
		(pad "B8" smd roundrect
			(at -1.75 3.5)
			(size 0.3 1.15)
			(layers "B.Cu" "B.Mask" "B.Paste")
			(roundrect_rratio 0.25)
			(net 36 "unconnected-(J1-SBU_{2}-PadB8)")
			(pinfunction "SBU_{2}")
			(pintype "bidirectional+no_connect")
		)
		(pad "B9" smd roundrect
			(at -2.4 3.5)
			(size 0.6 1.15)
			(layers "B.Cu" "B.Mask" "B.Paste")
			(roundrect_rratio 0.25)
			(net 6 "VBUS")
			(pinfunction "VBUS")
			(pintype "passive")
		)
		(pad "B12" smd roundrect
			(at -3.202 3.5)
			(size 0.6 1.15)
			(layers "B.Cu" "B.Mask" "B.Paste")
			(roundrect_rratio 0.25)
			(net 2 "GND")
			(pinfunction "GND")
			(pintype "passive")
		)
		(pad "SH" thru_hole oval
			(at -4.321 -1.255)
			(size 1 2)
			(drill oval 0.6 1.4)
			(layers "*.Cu" "*.Mask")
			(remove_unused_layers no)
			(net 2 "GND")
			(pinfunction "SH")
			(pintype "passive")
		)
		(pad "SH" thru_hole oval
			(at -4.321 2.926)
			(size 1.05 2.1)
			(drill oval 0.6 1.7)
			(layers "*.Cu" "*.Mask")
			(remove_unused_layers no)
			(net 2 "GND")
			(pinfunction "SH")
			(pintype "passive")
		)
		(pad "SH" thru_hole oval
			(at 4.32 -1.255)
			(size 1 2)
			(drill oval 0.6 1.4)
			(layers "*.Cu" "*.Mask")
			(remove_unused_layers no)
			(net 2 "GND")
			(pinfunction "SH")
			(pintype "passive")
		)
		(pad "SH" thru_hole oval
			(at 4.32 2.926)
			(size 1.05 2.1)
			(drill oval 0.6 1.7)
			(layers "*.Cu" "*.Mask")
			(remove_unused_layers no)
			(net 2 "GND")
			(pinfunction "SH")
			(pintype "passive")
		)
	)
	(footprint "antmicro-footprints:C_0805_2012Metric"
		(layer "B.Cu")
		(at 101.6 93.75 -90)
		(descr "Capacitor SMD 0805")
		(tags "capacitor SMD 0805")
		(property "Reference" "C30"
			(at -1.0908 -1.6764 90)
			(layer "B.SilkS")
			(effects
				(font
					(size 0.7 0.7)
					(thickness 0.15)
				)
				(justify left bottom mirror)
			)
		)
		(property "Value" "C_22u_25V_0805"
			(at -2.055717 -1.963152 90)
			(layer "B.Fab")
			(effects
				(font
					(size 0.7 0.7)
					(thickness 0.15)
				)
				(justify left bottom mirror)
			)
		)
		(property "Datasheet" "https://product.samsungsem.com/mlcc/CL21A226MAYNNN.do"
			(at 0 0 270)
			(layer "F.Fab")
			(hide yes)
			(effects
				(font
					(size 1.27 1.27)
					(thickness 0.15)
				)
			)
		)
		(property "Description" "SMT Multilayer Ceramic Capacitor, 22uF, +/-20%, 25V, X5R, 0805 [2012 Metric]"
			(at 0 0 270)
			(layer "F.Fab")
			(hide yes)
			(effects
				(font
					(size 1.27 1.27)
					(thickness 0.15)
				)
			)
		)
		(property "MPN" "CL21A226MAYNNNE"
			(at 0 0 270)
			(unlocked yes)
			(layer "B.Fab")
			(hide yes)
			(effects
				(font
					(size 1 1)
					(thickness 0.15)
				)
				(justify mirror)
			)
		)
		(property "Manufacturer" "Samsung Electro-Mechanics"
			(at 0 0 270)
			(unlocked yes)
			(layer "B.Fab")
			(hide yes)
			(effects
				(font
					(size 1 1)
					(thickness 0.15)
				)
				(justify mirror)
			)
		)
		(property "License" "Apache-2.0"
			(at 0 0 270)
			(unlocked yes)
			(layer "B.Fab")
			(hide yes)
			(effects
				(font
					(size 1 1)
					(thickness 0.15)
				)
				(justify mirror)
			)
		)
		(property "Author" "Antmicro"
			(at 0 0 270)
			(unlocked yes)
			(layer "B.Fab")
			(hide yes)
			(effects
				(font
					(size 1 1)
					(thickness 0.15)
				)
				(justify mirror)
			)
		)
		(property "Val" "22u"
			(at 0 0 270)
			(unlocked yes)
			(layer "B.Fab")
			(hide yes)
			(effects
				(font
					(size 1 1)
					(thickness 0.15)
				)
				(justify mirror)
			)
		)
		(property "Voltage" "25V"
			(at 0 0 270)
			(unlocked yes)
			(layer "B.Fab")
			(hide yes)
			(effects
				(font
					(size 1 1)
					(thickness 0.15)
				)
				(justify mirror)
			)
		)
		(property "Dielectric" "X5R"
			(at 0 0 270)
			(unlocked yes)
			(layer "B.Fab")
			(hide yes)
			(effects
				(font
					(size 1 1)
					(thickness 0.15)
				)
				(justify mirror)
			)
		)
		(property "Public" "False"
			(at 0 0 270)
			(unlocked yes)
			(layer "B.Fab")
			(hide yes)
			(effects
				(font
					(size 1 1)
					(thickness 0.15)
				)
				(justify mirror)
			)
		)
		(sheetname "/DC-DC Converters/")
		(sheetfile "dc-dc_converters.kicad_sch")
		(attr smd)
		(fp_line
			(start 0.3 0.7)
			(end -0.3 0.7)
			(stroke
				(width 0.15)
				(type solid)
			)
			(layer "B.SilkS")
		)
		(fp_line
			(start 0.3 -0.7)
			(end -0.3 -0.7)
			(stroke
				(width 0.15)
				(type solid)
			)
			(layer "B.SilkS")
		)
		(fp_rect
			(start 1.95 0.9)
			(end -1.95 -0.9)
			(stroke
				(width 0.05)
				(type default)
			)
			(fill no)
			(layer "B.CrtYd")
		)
		(fp_rect
			(start -0.95 0.675)
			(end 0.95 -0.675)
			(stroke
				(width 0.15)
				(type solid)
			)
			(fill no)
			(layer "B.Fab")
		)
		(pad "1" smd roundrect
			(at -1.1 0 270)
			(size 1.2 1.3)
			(layers "B.Cu" "B.Mask" "B.Paste")
			(roundrect_rratio 0.25)
			(net 2 "GND")
			(pintype "passive")
		)
		(pad "2" smd roundrect
			(at 1.1 0 270)
			(size 1.2 1.3)
			(layers "B.Cu" "B.Mask" "B.Paste")
			(roundrect_rratio 0.25)
			(net 5 "+12V")
			(pintype "passive")
		)
	)
	(footprint "antmicro-footprints:Conn_JST_SH_1x4_SM04B-SRSS-TB-LF-SN"
		(layer "B.Cu")
		(at 100.301 88.1 -90)
		(property "Reference" "J3"
			(at -2.35 2.15 180)
			(layer "B.SilkS")
			(effects
				(font
					(size 0.7 0.7)
					(thickness 0.15)
				)
				(justify left bottom mirror)
			)
		)
		(property "Value" "JST_SH_1x4_SM04B-SRSS-TB-LF-SN"
			(at 0 -3.9 90)
			(layer "B.Fab")
			(effects
				(font
					(size 0.7 0.7)
					(thickness 0.15)
				)
				(justify left bottom mirror)
			)
		)
		(property "Datasheet" "https://www.jst-mfg.com/product/pdf/eng/eSH.pdf"
			(at 0 0 270)
			(layer "F.Fab")
			(hide yes)
			(effects
				(font
					(size 1.27 1.27)
					(thickness 0.15)
				)
			)
		)
		(property "Description" "Pin Header, Right Angle, Wire-to-Board, 1 mm, 1 Rows, 4 Contacts, Surface Mount Right Angle, SH"
			(at 0 0 270)
			(layer "F.Fab")
			(hide yes)
			(effects
				(font
					(size 1.27 1.27)
					(thickness 0.15)
				)
			)
		)
		(property "MPN" "SM04B-SRSS-TB(LF)(SN)"
			(at 0 0 270)
			(unlocked yes)
			(layer "B.Fab")
			(hide yes)
			(effects
				(font
					(size 1 1)
					(thickness 0.15)
				)
				(justify mirror)
			)
		)
		(property "Manufacturer" "JST Automotive Connectors"
			(at 0 0 270)
			(unlocked yes)
			(layer "B.Fab")
			(hide yes)
			(effects
				(font
					(size 1 1)
					(thickness 0.15)
				)
				(justify mirror)
			)
		)
		(property "Author" "Antmicro"
			(at 0 0 270)
			(unlocked yes)
			(layer "B.Fab")
			(hide yes)
			(effects
				(font
					(size 1 1)
					(thickness 0.15)
				)
				(justify mirror)
			)
		)
		(property "License" "Apache-2.0"
			(at 0 0 270)
			(unlocked yes)
			(layer "B.Fab")
			(hide yes)
			(effects
				(font
					(size 1 1)
					(thickness 0.15)
				)
				(justify mirror)
			)
		)
		(sheetname "/DC-DC Converters/")
		(sheetfile "dc-dc_converters.kicad_sch")
		(attr smd)
		(fp_line
			(start -3.2 2)
			(end -2 2)
			(stroke
				(width 0.15)
				(type solid)
			)
			(layer "B.SilkS")
		)
		(fp_line
			(start 3.2 2)
			(end 2 2)
			(stroke
				(width 0.15)
				(type solid)
			)
			(layer "B.SilkS")
		)
		(fp_line
			(start -3.2 -0.6)
			(end -3.2 2)
			(stroke
				(width 0.15)
				(type solid)
			)
			(layer "B.SilkS")
		)
		(fp_line
			(start 3.2 -0.6)
			(end 3.2 2)
			(stroke
				(width 0.15)
				(type solid)
			)
			(layer "B.SilkS")
		)
		(fp_line
			(start 2 -2.6)
			(end -2 -2.6)
			(stroke
				(width 0.15)
				(type solid)
			)
			(layer "B.SilkS")
		)
		(fp_circle
			(center -2.1 2.5)
			(end -2.05 2.5)
			(stroke
				(width 0.15)
				(type solid)
			)
			(fill yes)
			(layer "B.SilkS")
		)
		(fp_rect
			(start -3.65 3.14)
			(end 3.65 -2.9)
			(stroke
				(width 0.05)
				(type solid)
			)
			(fill no)
			(layer "B.CrtYd")
		)
		(fp_rect
			(start -3 2.475)
			(end 3 -2.475)
			(stroke
				(width 0.15)
				(type solid)
			)
			(fill no)
			(layer "B.Fab")
		)
		(pad "1" smd roundrect
			(at -1.5 2.12 90)
			(size 0.6 1.55)
			(layers "B.Cu" "B.Mask" "B.Paste")
			(roundrect_rratio 0.25)
			(net 2 "GND")
			(pintype "passive")
		)
		(pad "2" smd roundrect
			(at -0.5 2.12 90)
			(size 0.6 1.55)
			(layers "B.Cu" "B.Mask" "B.Paste")
			(roundrect_rratio 0.25)
			(net 1 "+3V3")
			(pintype "passive")
		)
		(pad "3" smd roundrect
			(at 0.5 2.12 90)
			(size 0.6 1.55)
			(layers "B.Cu" "B.Mask" "B.Paste")
			(roundrect_rratio 0.25)
			(net 2 "GND")
			(pintype "passive")
		)
		(pad "4" smd roundrect
			(at 1.5 2.12 90)
			(size 0.6 1.55)
			(layers "B.Cu" "B.Mask" "B.Paste")
			(roundrect_rratio 0.25)
			(net 25 "+5V")
			(pintype "passive")
		)
		(pad "MP" smd roundrect
			(at -2.8 -1.755 270)
			(size 1.2 1.8)
			(layers "B.Cu" "B.Mask" "B.Paste")
			(roundrect_rratio 0.25)
			(net 2 "GND")
			(pintype "passive")
		)
		(pad "MP" smd roundrect
			(at 2.8 -1.755 270)
			(size 1.2 1.8)
			(layers "B.Cu" "B.Mask" "B.Paste")
			(roundrect_rratio 0.25)
			(net 2 "GND")
			(pintype "passive")
		)
	)
	(footprint "antmicro-footprints:C_0805_2012Metric"
		(layer "B.Cu")
		(at 96.15 93.05 -90)
		(descr "Capacitor SMD 0805")
		(tags "capacitor SMD 0805")
		(property "Reference" "C38"
			(at -21.295 12.074 180)
			(layer "B.SilkS")
			(effects
				(font
					(size 0.7 0.7)
					(thickness 0.15)
				)
				(justify left bottom mirror)
			)
		)
		(property "Value" "C_22u_25V_0805"
			(at -2.055717 -1.963152 90)
			(layer "B.Fab")
			(effects
				(font
					(size 0.7 0.7)
					(thickness 0.15)
				)
				(justify left bottom mirror)
			)
		)
		(property "Datasheet" "https://product.samsungsem.com/mlcc/CL21A226MAYNNN.do"
			(at 0 0 270)
			(layer "F.Fab")
			(hide yes)
			(effects
				(font
					(size 1.27 1.27)
					(thickness 0.15)
				)
			)
		)
		(property "Description" "SMT Multilayer Ceramic Capacitor, 22uF, +/-20%, 25V, X5R, 0805 [2012 Metric]"
			(at 0 0 270)
			(layer "F.Fab")
			(hide yes)
			(effects
				(font
					(size 1.27 1.27)
					(thickness 0.15)
				)
			)
		)
		(property "MPN" "CL21A226MAYNNNE"
			(at 0 0 270)
			(unlocked yes)
			(layer "B.Fab")
			(hide yes)
			(effects
				(font
					(size 1 1)
					(thickness 0.15)
				)
				(justify mirror)
			)
		)
		(property "Manufacturer" "Samsung Electro-Mechanics"
			(at 0 0 270)
			(unlocked yes)
			(layer "B.Fab")
			(hide yes)
			(effects
				(font
					(size 1 1)
					(thickness 0.15)
				)
				(justify mirror)
			)
		)
		(property "License" "Apache-2.0"
			(at 0 0 270)
			(unlocked yes)
			(layer "B.Fab")
			(hide yes)
			(effects
				(font
					(size 1 1)
					(thickness 0.15)
				)
				(justify mirror)
			)
		)
		(property "Author" "Antmicro"
			(at 0 0 270)
			(unlocked yes)
			(layer "B.Fab")
			(hide yes)
			(effects
				(font
					(size 1 1)
					(thickness 0.15)
				)
				(justify mirror)
			)
		)
		(property "Val" "22u"
			(at 0 0 270)
			(unlocked yes)
			(layer "B.Fab")
			(hide yes)
			(effects
				(font
					(size 1 1)
					(thickness 0.15)
				)
				(justify mirror)
			)
		)
		(property "Voltage" "25V"
			(at 0 0 270)
			(unlocked yes)
			(layer "B.Fab")
			(hide yes)
			(effects
				(font
					(size 1 1)
					(thickness 0.15)
				)
				(justify mirror)
			)
		)
		(property "Dielectric" "X5R"
			(at 0 0 270)
			(unlocked yes)
			(layer "B.Fab")
			(hide yes)
			(effects
				(font
					(size 1 1)
					(thickness 0.15)
				)
				(justify mirror)
			)
		)
		(property "Public" "False"
			(at 0 0 270)
			(unlocked yes)
			(layer "B.Fab")
			(hide yes)
			(effects
				(font
					(size 1 1)
					(thickness 0.15)
				)
				(justify mirror)
			)
		)
		(sheetname "/DC-DC Converters/")
		(sheetfile "dc-dc_converters.kicad_sch")
		(attr smd)
		(fp_line
			(start 0.3 0.7)
			(end -0.3 0.7)
			(stroke
				(width 0.15)
				(type solid)
			)
			(layer "B.SilkS")
		)
		(fp_line
			(start 0.3 -0.7)
			(end -0.3 -0.7)
			(stroke
				(width 0.15)
				(type solid)
			)
			(layer "B.SilkS")
		)
		(fp_rect
			(start 1.95 0.9)
			(end -1.95 -0.9)
			(stroke
				(width 0.05)
				(type default)
			)
			(fill no)
			(layer "B.CrtYd")
		)
		(fp_rect
			(start -0.95 0.675)
			(end 0.95 -0.675)
			(stroke
				(width 0.15)
				(type solid)
			)
			(fill no)
			(layer "B.Fab")
		)
		(pad "1" smd roundrect
			(at -1.1 0 270)
			(size 1.2 1.3)
			(layers "B.Cu" "B.Mask" "B.Paste")
			(roundrect_rratio 0.25)
			(net 2 "GND")
			(pintype "passive")
		)
		(pad "2" smd roundrect
			(at 1.1 0 270)
			(size 1.2 1.3)
			(layers "B.Cu" "B.Mask" "B.Paste")
			(roundrect_rratio 0.25)
			(net 5 "+12V")
			(pintype "passive")
		)
	)
	(footprint "antmicro-footprints:R_0402_1005Metric"
		(layer "B.Cu")
		(at 88.351 86.7 90)
		(descr "Resistor SMD 0402")
		(tags "resistor SMD 0402")
		(property "Reference" "R10"
			(at 1.083 3.051 90)
			(layer "B.SilkS")
			(effects
				(font
					(size 0.7 0.7)
					(thickness 0.15)
				)
				(justify left bottom mirror)
			)
		)
		(property "Value" "R_100k_0402"
			(at -1.011843 -1.772047 90)
			(layer "B.Fab")
			(effects
				(font
					(size 0.7 0.7)
					(thickness 0.15)
				)
				(justify right bottom mirror)
			)
		)
		(property "Datasheet" "https://www.bourns.com/docs/product-datasheets/cr.pdf"
			(at 0 0 90)
			(layer "F.Fab")
			(hide yes)
			(effects
				(font
					(size 1.27 1.27)
					(thickness 0.15)
				)
			)
		)
		(property "Description" "SMD Chip Resistor, 100 kohm, ± 1%, 62.5 mW, 0402 [1005 Metric], Thick Film, General Purpose"
			(at 0 0 90)
			(layer "F.Fab")
			(hide yes)
			(effects
				(font
					(size 1.27 1.27)
					(thickness 0.15)
				)
			)
		)
		(property "MPN" "CR0402-FX-1003GLF"
			(at 0 0 90)
			(unlocked yes)
			(layer "B.Fab")
			(hide yes)
			(effects
				(font
					(size 1 1)
					(thickness 0.15)
				)
				(justify mirror)
			)
		)
		(property "Manufacturer" "Bourns"
			(at 0 0 90)
			(unlocked yes)
			(layer "B.Fab")
			(hide yes)
			(effects
				(font
					(size 1 1)
					(thickness 0.15)
				)
				(justify mirror)
			)
		)
		(property "License" "Apache-2.0"
			(at 0 0 90)
			(unlocked yes)
			(layer "B.Fab")
			(hide yes)
			(effects
				(font
					(size 1 1)
					(thickness 0.15)
				)
				(justify mirror)
			)
		)
		(property "Author" "Antmicro"
			(at 0 0 90)
			(unlocked yes)
			(layer "B.Fab")
			(hide yes)
			(effects
				(font
					(size 1 1)
					(thickness 0.15)
				)
				(justify mirror)
			)
		)
		(property "Val" "100k"
			(at 0 0 90)
			(unlocked yes)
			(layer "B.Fab")
			(hide yes)
			(effects
				(font
					(size 1 1)
					(thickness 0.15)
				)
				(justify mirror)
			)
		)
		(property "Tolerance" "1%"
			(at 0 0 90)
			(unlocked yes)
			(layer "B.Fab")
			(hide yes)
			(effects
				(font
					(size 1 1)
					(thickness 0.15)
				)
				(justify mirror)
			)
		)
		(sheetname "/DC-DC Converters/")
		(sheetfile "dc-dc_converters.kicad_sch")
		(attr smd)
		(fp_rect
			(start -0.925 0.47)
			(end 0.925 -0.47)
			(stroke
				(width 0.05)
				(type default)
			)
			(fill no)
			(layer "B.CrtYd")
		)
		(fp_rect
			(start -0.5 0.25)
			(end 0.5 -0.25)
			(stroke
				(width 0.15)
				(type solid)
			)
			(fill no)
			(layer "B.Fab")
		)
		(pad "1" smd roundrect
			(at -0.48 0 90)
			(size 0.59 0.64)
			(layers "B.Cu" "B.Mask" "B.Paste")
			(roundrect_rratio 0.25)
			(net 47 "Net-(U3-EN)")
			(pintype "passive")
		)
		(pad "2" smd roundrect
			(at 0.48 0 90)
			(size 0.59 0.64)
			(layers "B.Cu" "B.Mask" "B.Paste")
			(roundrect_rratio 0.25)
			(net 5 "+12V")
			(pintype "passive")
		)
	)
	(footprint "antmicro-footprints:R_0402_1005Metric"
		(layer "B.Cu")
		(at 85.85 84.25 180)
		(descr "Resistor SMD 0402")
		(tags "resistor SMD 0402")
		(property "Reference" "R11"
			(at -0.826 -0.4 0)
			(layer "B.SilkS")
			(effects
				(font
					(size 0.7 0.7)
					(thickness 0.15)
				)
				(justify right bottom mirror)
			)
		)
		(property "Value" "R_100k_0402"
			(at -1.011843 -1.772047 0)
			(layer "B.Fab")
			(effects
				(font
					(size 0.7 0.7)
					(thickness 0.15)
				)
				(justify left bottom mirror)
			)
		)
		(property "Datasheet" "https://www.bourns.com/docs/product-datasheets/cr.pdf"
			(at 0 0 180)
			(layer "F.Fab")
			(hide yes)
			(effects
				(font
					(size 1.27 1.27)
					(thickness 0.15)
				)
			)
		)
		(property "Description" "SMD Chip Resistor, 100 kohm, ± 1%, 62.5 mW, 0402 [1005 Metric], Thick Film, General Purpose"
			(at 0 0 180)
			(layer "F.Fab")
			(hide yes)
			(effects
				(font
					(size 1.27 1.27)
					(thickness 0.15)
				)
			)
		)
		(property "MPN" "CR0402-FX-1003GLF"
			(at 0 0 180)
			(unlocked yes)
			(layer "B.Fab")
			(hide yes)
			(effects
				(font
					(size 1 1)
					(thickness 0.15)
				)
				(justify mirror)
			)
		)
		(property "Manufacturer" "Bourns"
			(at 0 0 180)
			(unlocked yes)
			(layer "B.Fab")
			(hide yes)
			(effects
				(font
					(size 1 1)
					(thickness 0.15)
				)
				(justify mirror)
			)
		)
		(property "License" "Apache-2.0"
			(at 0 0 180)
			(unlocked yes)
			(layer "B.Fab")
			(hide yes)
			(effects
				(font
					(size 1 1)
					(thickness 0.15)
				)
				(justify mirror)
			)
		)
		(property "Author" "Antmicro"
			(at 0 0 180)
			(unlocked yes)
			(layer "B.Fab")
			(hide yes)
			(effects
				(font
					(size 1 1)
					(thickness 0.15)
				)
				(justify mirror)
			)
		)
		(property "Val" "100k"
			(at 0 0 180)
			(unlocked yes)
			(layer "B.Fab")
			(hide yes)
			(effects
				(font
					(size 1 1)
					(thickness 0.15)
				)
				(justify mirror)
			)
		)
		(property "Tolerance" "1%"
			(at 0 0 180)
			(unlocked yes)
			(layer "B.Fab")
			(hide yes)
			(effects
				(font
					(size 1 1)
					(thickness 0.15)
				)
				(justify mirror)
			)
		)
		(sheetname "/DC-DC Converters/")
		(sheetfile "dc-dc_converters.kicad_sch")
		(attr smd)
		(fp_rect
			(start -0.925 0.47)
			(end 0.925 -0.47)
			(stroke
				(width 0.05)
				(type default)
			)
			(fill no)
			(layer "B.CrtYd")
		)
		(fp_rect
			(start -0.5 0.25)
			(end 0.5 -0.25)
			(stroke
				(width 0.15)
				(type solid)
			)
			(fill no)
			(layer "B.Fab")
		)
		(pad "1" smd roundrect
			(at -0.48 0 180)
			(size 0.59 0.64)
			(layers "B.Cu" "B.Mask" "B.Paste")
			(roundrect_rratio 0.25)
			(net 9 "Net-(U4-EN)")
			(pintype "passive")
		)
		(pad "2" smd roundrect
			(at 0.48 0 180)
			(size 0.59 0.64)
			(layers "B.Cu" "B.Mask" "B.Paste")
			(roundrect_rratio 0.25)
			(net 5 "+12V")
			(pintype "passive")
		)
	)
	(footprint "antmicro-footprints:F_1206_3216Metric"
		(layer "B.Cu")
		(at 85.8 95.7 -90)
		(property "Reference" "F1"
			(at 3.65 0.724 180)
			(layer "B.SilkS")
			(effects
				(font
					(size 0.7 0.7)
					(thickness 0.15)
				)
				(justify right bottom mirror)
			)
		)
		(property "Value" "F_7A_1206"
			(at 0 -2 90)
			(layer "B.Fab")
			(effects
				(font
					(size 0.7 0.7)
					(thickness 0.15)
				)
				(justify left bottom mirror)
			)
		)
		(property "Datasheet" "https://us.schurter.com/pdf/english/typ_UST_1206.pdf"
			(at 0 0 270)
			(layer "F.Fab")
			(hide yes)
			(effects
				(font
					(size 1.27 1.27)
					(thickness 0.15)
				)
			)
		)
		(property "Description" "7 A 32 V AC 63 V DC Fuse Board Mount (Cartridge Style Excluded) Surface Mount 1206 (3216 Metric)"
			(at 0 0 270)
			(layer "F.Fab")
			(hide yes)
			(effects
				(font
					(size 1.27 1.27)
					(thickness 0.15)
				)
			)
		)
		(property "Manufacturer" "Schurter"
			(at 0 0 270)
			(unlocked yes)
			(layer "B.Fab")
			(hide yes)
			(effects
				(font
					(size 1 1)
					(thickness 0.15)
				)
				(justify mirror)
			)
		)
		(property "MPN" "3413.0326.11"
			(at 0 0 270)
			(unlocked yes)
			(layer "B.Fab")
			(hide yes)
			(effects
				(font
					(size 1 1)
					(thickness 0.15)
				)
				(justify mirror)
			)
		)
		(property "Author" "Antmicro"
			(at 0 0 270)
			(unlocked yes)
			(layer "B.Fab")
			(hide yes)
			(effects
				(font
					(size 1 1)
					(thickness 0.15)
				)
				(justify mirror)
			)
		)
		(property "License" "Apache-2.0"
			(at 0 0 270)
			(unlocked yes)
			(layer "B.Fab")
			(hide yes)
			(effects
				(font
					(size 1 1)
					(thickness 0.15)
				)
				(justify mirror)
			)
		)
		(sheetname "/DC-DC Converters/")
		(sheetfile "dc-dc_converters.kicad_sch")
		(attr smd)
		(fp_line
			(start -0.8 0.899)
			(end 0.8 0.899)
			(stroke
				(width 0.15)
				(type solid)
			)
			(layer "B.SilkS")
		)
		(fp_line
			(start -0.8 -0.901)
			(end 0.8 -0.901)
			(stroke
				(width 0.15)
				(type solid)
			)
			(layer "B.SilkS")
		)
		(fp_rect
			(start -2.325 1.15)
			(end 2.325 -1.15)
			(stroke
				(width 0.05)
				(type default)
			)
			(fill no)
			(layer "B.CrtYd")
		)
		(fp_line
			(start -1.677 0.861)
			(end -1.677 -0.792)
			(stroke
				(width 0.15)
				(type solid)
			)
			(layer "B.Fab")
		)
		(fp_line
			(start 1.624 0.861)
			(end -1.677 0.861)
			(stroke
				(width 0.15)
				(type solid)
			)
			(layer "B.Fab")
		)
		(fp_line
			(start -1.677 -0.792)
			(end 1.624 -0.792)
			(stroke
				(width 0.15)
				(type solid)
			)
			(layer "B.Fab")
		)
		(fp_line
			(start 1.624 -0.792)
			(end 1.624 0.861)
			(stroke
				(width 0.15)
				(type solid)
			)
			(layer "B.Fab")
		)
		(pad "1" smd roundrect
			(at -1.5 -0.001 270)
			(size 1.15 1.8)
			(layers "B.Cu" "B.Mask" "B.Paste")
			(roundrect_rratio 0.25)
			(net 5 "+12V")
			(pintype "passive")
		)
		(pad "2" smd roundrect
			(at 1.5 -0.001 270)
			(size 1.15 1.8)
			(layers "B.Cu" "B.Mask" "B.Paste")
			(roundrect_rratio 0.25)
			(net 26 "Net-(D5-C)")
			(pintype "passive")
		)
	)
	(footprint "antmicro-footprints:C_0805_2012Metric"
		(layer "B.Cu")
		(at 94.35 93.05 -90)
		(descr "Capacitor SMD 0805")
		(tags "capacitor SMD 0805")
		(property "Reference" "C35"
			(at -20.279 10.274 180)
			(layer "B.SilkS")
			(effects
				(font
					(size 0.7 0.7)
					(thickness 0.15)
				)
				(justify left bottom mirror)
			)
		)
		(property "Value" "C_22u_25V_0805"
			(at -2.055717 -1.963152 90)
			(layer "B.Fab")
			(effects
				(font
					(size 0.7 0.7)
					(thickness 0.15)
				)
				(justify left bottom mirror)
			)
		)
		(property "Datasheet" "https://product.samsungsem.com/mlcc/CL21A226MAYNNN.do"
			(at 0 0 270)
			(layer "F.Fab")
			(hide yes)
			(effects
				(font
					(size 1.27 1.27)
					(thickness 0.15)
				)
			)
		)
		(property "Description" "SMT Multilayer Ceramic Capacitor, 22uF, +/-20%, 25V, X5R, 0805 [2012 Metric]"
			(at 0 0 270)
			(layer "F.Fab")
			(hide yes)
			(effects
				(font
					(size 1.27 1.27)
					(thickness 0.15)
				)
			)
		)
		(property "MPN" "CL21A226MAYNNNE"
			(at 0 0 270)
			(unlocked yes)
			(layer "B.Fab")
			(hide yes)
			(effects
				(font
					(size 1 1)
					(thickness 0.15)
				)
				(justify mirror)
			)
		)
		(property "Manufacturer" "Samsung Electro-Mechanics"
			(at 0 0 270)
			(unlocked yes)
			(layer "B.Fab")
			(hide yes)
			(effects
				(font
					(size 1 1)
					(thickness 0.15)
				)
				(justify mirror)
			)
		)
		(property "License" "Apache-2.0"
			(at 0 0 270)
			(unlocked yes)
			(layer "B.Fab")
			(hide yes)
			(effects
				(font
					(size 1 1)
					(thickness 0.15)
				)
				(justify mirror)
			)
		)
		(property "Author" "Antmicro"
			(at 0 0 270)
			(unlocked yes)
			(layer "B.Fab")
			(hide yes)
			(effects
				(font
					(size 1 1)
					(thickness 0.15)
				)
				(justify mirror)
			)
		)
		(property "Val" "22u"
			(at 0 0 270)
			(unlocked yes)
			(layer "B.Fab")
			(hide yes)
			(effects
				(font
					(size 1 1)
					(thickness 0.15)
				)
				(justify mirror)
			)
		)
		(property "Voltage" "25V"
			(at 0 0 270)
			(unlocked yes)
			(layer "B.Fab")
			(hide yes)
			(effects
				(font
					(size 1 1)
					(thickness 0.15)
				)
				(justify mirror)
			)
		)
		(property "Dielectric" "X5R"
			(at 0 0 270)
			(unlocked yes)
			(layer "B.Fab")
			(hide yes)
			(effects
				(font
					(size 1 1)
					(thickness 0.15)
				)
				(justify mirror)
			)
		)
		(property "Public" "False"
			(at 0 0 270)
			(unlocked yes)
			(layer "B.Fab")
			(hide yes)
			(effects
				(font
					(size 1 1)
					(thickness 0.15)
				)
				(justify mirror)
			)
		)
		(sheetname "/DC-DC Converters/")
		(sheetfile "dc-dc_converters.kicad_sch")
		(attr smd)
		(fp_line
			(start 0.3 0.7)
			(end -0.3 0.7)
			(stroke
				(width 0.15)
				(type solid)
			)
			(layer "B.SilkS")
		)
		(fp_line
			(start 0.3 -0.7)
			(end -0.3 -0.7)
			(stroke
				(width 0.15)
				(type solid)
			)
			(layer "B.SilkS")
		)
		(fp_rect
			(start 1.95 0.9)
			(end -1.95 -0.9)
			(stroke
				(width 0.05)
				(type default)
			)
			(fill no)
			(layer "B.CrtYd")
		)
		(fp_rect
			(start -0.95 0.675)
			(end 0.95 -0.675)
			(stroke
				(width 0.15)
				(type solid)
			)
			(fill no)
			(layer "B.Fab")
		)
		(pad "1" smd roundrect
			(at -1.1 0 270)
			(size 1.2 1.3)
			(layers "B.Cu" "B.Mask" "B.Paste")
			(roundrect_rratio 0.25)
			(net 2 "GND")
			(pintype "passive")
		)
		(pad "2" smd roundrect
			(at 1.1 0 270)
			(size 1.2 1.3)
			(layers "B.Cu" "B.Mask" "B.Paste")
			(roundrect_rratio 0.25)
			(net 5 "+12V")
			(pintype "passive")
		)
	)
	(footprint "antmicro-footprints:C_0805_2012Metric"
		(layer "B.Cu")
		(at 101.55 98.2 90)
		(descr "Capacitor SMD 0805")
		(tags "capacitor SMD 0805")
		(property "Reference" "C33"
			(at 1.807 -0.458 180)
			(layer "B.SilkS")
			(effects
				(font
					(size 0.7 0.7)
					(thickness 0.15)
				)
				(justify right bottom mirror)
			)
		)
		(property "Value" "C_22u_25V_0805"
			(at -2.055717 -1.963152 90)
			(layer "B.Fab")
			(effects
				(font
					(size 0.7 0.7)
					(thickness 0.15)
				)
				(justify right bottom mirror)
			)
		)
		(property "Datasheet" "https://product.samsungsem.com/mlcc/CL21A226MAYNNN.do"
			(at 0 0 90)
			(layer "F.Fab")
			(hide yes)
			(effects
				(font
					(size 1.27 1.27)
					(thickness 0.15)
				)
			)
		)
		(property "Description" "SMT Multilayer Ceramic Capacitor, 22uF, +/-20%, 25V, X5R, 0805 [2012 Metric]"
			(at 0 0 90)
			(layer "F.Fab")
			(hide yes)
			(effects
				(font
					(size 1.27 1.27)
					(thickness 0.15)
				)
			)
		)
		(property "MPN" "CL21A226MAYNNNE"
			(at 0 0 90)
			(unlocked yes)
			(layer "B.Fab")
			(hide yes)
			(effects
				(font
					(size 1 1)
					(thickness 0.15)
				)
				(justify mirror)
			)
		)
		(property "Manufacturer" "Samsung Electro-Mechanics"
			(at 0 0 90)
			(unlocked yes)
			(layer "B.Fab")
			(hide yes)
			(effects
				(font
					(size 1 1)
					(thickness 0.15)
				)
				(justify mirror)
			)
		)
		(property "License" "Apache-2.0"
			(at 0 0 90)
			(unlocked yes)
			(layer "B.Fab")
			(hide yes)
			(effects
				(font
					(size 1 1)
					(thickness 0.15)
				)
				(justify mirror)
			)
		)
		(property "Author" "Antmicro"
			(at 0 0 90)
			(unlocked yes)
			(layer "B.Fab")
			(hide yes)
			(effects
				(font
					(size 1 1)
					(thickness 0.15)
				)
				(justify mirror)
			)
		)
		(property "Val" "22u"
			(at 0 0 90)
			(unlocked yes)
			(layer "B.Fab")
			(hide yes)
			(effects
				(font
					(size 1 1)
					(thickness 0.15)
				)
				(justify mirror)
			)
		)
		(property "Voltage" "25V"
			(at 0 0 90)
			(unlocked yes)
			(layer "B.Fab")
			(hide yes)
			(effects
				(font
					(size 1 1)
					(thickness 0.15)
				)
				(justify mirror)
			)
		)
		(property "Dielectric" "X5R"
			(at 0 0 90)
			(unlocked yes)
			(layer "B.Fab")
			(hide yes)
			(effects
				(font
					(size 1 1)
					(thickness 0.15)
				)
				(justify mirror)
			)
		)
		(property "Public" "False"
			(at 0 0 90)
			(unlocked yes)
			(layer "B.Fab")
			(hide yes)
			(effects
				(font
					(size 1 1)
					(thickness 0.15)
				)
				(justify mirror)
			)
		)
		(sheetname "/DC-DC Converters/")
		(sheetfile "dc-dc_converters.kicad_sch")
		(attr smd)
		(fp_line
			(start 0.3 -0.7)
			(end -0.3 -0.7)
			(stroke
				(width 0.15)
				(type solid)
			)
			(layer "B.SilkS")
		)
		(fp_line
			(start 0.3 0.7)
			(end -0.3 0.7)
			(stroke
				(width 0.15)
				(type solid)
			)
			(layer "B.SilkS")
		)
		(fp_rect
			(start 1.95 0.9)
			(end -1.95 -0.9)
			(stroke
				(width 0.05)
				(type default)
			)
			(fill no)
			(layer "B.CrtYd")
		)
		(fp_rect
			(start -0.95 0.675)
			(end 0.95 -0.675)
			(stroke
				(width 0.15)
				(type solid)
			)
			(fill no)
			(layer "B.Fab")
		)
		(pad "1" smd roundrect
			(at -1.1 0 90)
			(size 1.2 1.3)
			(layers "B.Cu" "B.Mask" "B.Paste")
			(roundrect_rratio 0.25)
			(net 2 "GND")
			(pintype "passive")
		)
		(pad "2" smd roundrect
			(at 1.1 0 90)
			(size 1.2 1.3)
			(layers "B.Cu" "B.Mask" "B.Paste")
			(roundrect_rratio 0.25)
			(net 5 "+12V")
			(pintype "passive")
		)
	)
	(footprint "antmicro-footprints:C_0402_1005Metric"
		(layer "B.Cu")
		(at 91.851 68.6 180)
		(descr "Capacitor SMD 0402")
		(tags "capacitor SMD 0402")
		(property "Reference" "C27"
			(at 0.825 -0.45 0)
			(layer "B.SilkS")
			(effects
				(font
					(size 0.7 0.7)
					(thickness 0.15)
				)
				(justify left bottom mirror)
			)
		)
		(property "Value" "C_4u7_25V_0402"
			(at -1.022927 -2.155213 0)
			(layer "B.Fab")
			(effects
				(font
					(size 0.7 0.7)
					(thickness 0.15)
				)
				(justify left bottom mirror)
			)
		)
		(property "Datasheet" "https://www.murata.com/products/productdetail?partno=GRM155C61E475ME15%23"
			(at 0 0 180)
			(layer "F.Fab")
			(hide yes)
			(effects
				(font
					(size 1.27 1.27)
					(thickness 0.15)
				)
			)
		)
		(property "Description" "SMD Multilayer Ceramic Capacitor"
			(at 0 0 180)
			(layer "F.Fab")
			(hide yes)
			(effects
				(font
					(size 1.27 1.27)
					(thickness 0.15)
				)
			)
		)
		(property "MPN" "GRM155C61E475ME15J"
			(at 0 0 180)
			(unlocked yes)
			(layer "B.Fab")
			(hide yes)
			(effects
				(font
					(size 1 1)
					(thickness 0.15)
				)
				(justify mirror)
			)
		)
		(property "Manufacturer" "Murata"
			(at 0 0 180)
			(unlocked yes)
			(layer "B.Fab")
			(hide yes)
			(effects
				(font
					(size 1 1)
					(thickness 0.15)
				)
				(justify mirror)
			)
		)
		(property "License" "Apache-2.0"
			(at 0 0 180)
			(unlocked yes)
			(layer "B.Fab")
			(hide yes)
			(effects
				(font
					(size 1 1)
					(thickness 0.15)
				)
				(justify mirror)
			)
		)
		(property "Author" "Antmicro"
			(at 0 0 180)
			(unlocked yes)
			(layer "B.Fab")
			(hide yes)
			(effects
				(font
					(size 1 1)
					(thickness 0.15)
				)
				(justify mirror)
			)
		)
		(property "Val" "4u7"
			(at 0 0 180)
			(unlocked yes)
			(layer "B.Fab")
			(hide yes)
			(effects
				(font
					(size 1 1)
					(thickness 0.15)
				)
				(justify mirror)
			)
		)
		(property "Voltage" "25V"
			(at 0 0 180)
			(unlocked yes)
			(layer "B.Fab")
			(hide yes)
			(effects
				(font
					(size 1 1)
					(thickness 0.15)
				)
				(justify mirror)
			)
		)
		(property "Dielectric" "X5S"
			(at 0 0 180)
			(unlocked yes)
			(layer "B.Fab")
			(hide yes)
			(effects
				(font
					(size 1 1)
					(thickness 0.15)
				)
				(justify mirror)
			)
		)
		(sheetname "/USB PD/")
		(sheetfile "usb_pd.kicad_sch")
		(attr smd)
		(fp_rect
			(start -0.925 0.47)
			(end 0.925 -0.47)
			(stroke
				(width 0.05)
				(type default)
			)
			(fill no)
			(layer "B.CrtYd")
		)
		(fp_line
			(start 0.504 0.25)
			(end -0.494 0.25)
			(stroke
				(width 0.15)
				(type solid)
			)
			(layer "B.Fab")
		)
		(fp_line
			(start 0.504 -0.248)
			(end 0.504 0.25)
			(stroke
				(width 0.15)
				(type solid)
			)
			(layer "B.Fab")
		)
		(fp_line
			(start -0.494 0.25)
			(end -0.494 -0.248)
			(stroke
				(width 0.15)
				(type solid)
			)
			(layer "B.Fab")
		)
		(fp_line
			(start -0.494 -0.248)
			(end 0.504 -0.248)
			(stroke
				(width 0.15)
				(type solid)
			)
			(layer "B.Fab")
		)
		(pad "1" smd roundrect
			(at -0.48 0 180)
			(size 0.59 0.64)
			(layers "B.Cu" "B.Mask" "B.Paste")
			(roundrect_rratio 0.25)
			(net 2 "GND")
			(pintype "passive")
		)
		(pad "2" smd roundrect
			(at 0.48 0 180)
			(size 0.59 0.64)
			(layers "B.Cu" "B.Mask" "B.Paste")
			(roundrect_rratio 0.25)
			(net 6 "VBUS")
			(pintype "passive")
		)
	)
	(footprint "antmicro-footprints:R_0402_1005Metric"
		(layer "B.Cu")
		(at 88.576 89.1 -90)
		(descr "Resistor SMD 0402")
		(tags "resistor SMD 0402")
		(property "Reference" "R41"
			(at -0.85 -2.7 90)
			(layer "B.SilkS")
			(effects
				(font
					(size 0.7 0.7)
					(thickness 0.15)
				)
				(justify left bottom mirror)
			)
		)
		(property "Value" "R_1k_0402"
			(at -1.011843 -1.772047 90)
			(layer "B.Fab")
			(effects
				(font
					(size 0.7 0.7)
					(thickness 0.15)
				)
				(justify left bottom mirror)
			)
		)
		(property "Datasheet" "https://www.bourns.com/docs/product-datasheets/cr.pdf"
			(at 0 0 270)
			(layer "F.Fab")
			(hide yes)
			(effects
				(font
					(size 1.27 1.27)
					(thickness 0.15)
				)
			)
		)
		(property "Description" "SMD Chip Resistor, 1 kohm, ± 1%, 63 mW, 0402 [1005 Metric], Thick Film, General Purpose"
			(at 0 0 270)
			(layer "F.Fab")
			(hide yes)
			(effects
				(font
					(size 1.27 1.27)
					(thickness 0.15)
				)
			)
		)
		(property "MPN" "CR0402-FX-1001GLF"
			(at 0 0 270)
			(unlocked yes)
			(layer "B.Fab")
			(hide yes)
			(effects
				(font
					(size 1 1)
					(thickness 0.15)
				)
				(justify mirror)
			)
		)
		(property "Manufacturer" "Bourns"
			(at 0 0 270)
			(unlocked yes)
			(layer "B.Fab")
			(hide yes)
			(effects
				(font
					(size 1 1)
					(thickness 0.15)
				)
				(justify mirror)
			)
		)
		(property "License" "Apache-2.0"
			(at 0 0 270)
			(unlocked yes)
			(layer "B.Fab")
			(hide yes)
			(effects
				(font
					(size 1 1)
					(thickness 0.15)
				)
				(justify mirror)
			)
		)
		(property "Author" "Antmicro"
			(at 0 0 270)
			(unlocked yes)
			(layer "B.Fab")
			(hide yes)
			(effects
				(font
					(size 1 1)
					(thickness 0.15)
				)
				(justify mirror)
			)
		)
		(property "Val" "1k"
			(at 0 0 270)
			(unlocked yes)
			(layer "B.Fab")
			(hide yes)
			(effects
				(font
					(size 1 1)
					(thickness 0.15)
				)
				(justify mirror)
			)
		)
		(property "Tolerance" "1%"
			(at 0 0 270)
			(unlocked yes)
			(layer "B.Fab")
			(hide yes)
			(effects
				(font
					(size 1 1)
					(thickness 0.15)
				)
				(justify mirror)
			)
		)
		(sheetname "/DC-DC Converters/")
		(sheetfile "dc-dc_converters.kicad_sch")
		(attr smd)
		(fp_rect
			(start -0.925 0.47)
			(end 0.925 -0.47)
			(stroke
				(width 0.05)
				(type default)
			)
			(fill no)
			(layer "B.CrtYd")
		)
		(fp_rect
			(start -0.5 0.25)
			(end 0.5 -0.25)
			(stroke
				(width 0.15)
				(type solid)
			)
			(fill no)
			(layer "B.Fab")
		)
		(pad "1" smd roundrect
			(at -0.48 0 270)
			(size 0.59 0.64)
			(layers "B.Cu" "B.Mask" "B.Paste")
			(roundrect_rratio 0.25)
			(net 2 "GND")
			(pintype "passive")
		)
		(pad "2" smd roundrect
			(at 0.48 0 270)
			(size 0.59 0.64)
			(layers "B.Cu" "B.Mask" "B.Paste")
			(roundrect_rratio 0.25)
			(net 40 "Net-(U3-FB)")
			(pintype "passive")
		)
	)
	(footprint "antmicro-footprints:C_0603_1608Metric"
		(layer "B.Cu")
		(at 83.276 88.475 180)
		(descr "Capacitor SMD 0603")
		(tags "capacitor 0603")
		(property "Reference" "C25"
			(at -1.524 -1.525 180)
			(layer "B.SilkS")
			(effects
				(font
					(size 0.7 0.7)
					(thickness 0.15)
				)
				(justify left bottom mirror)
			)
		)
		(property "Value" "C_10u_25V_0603"
			(at -1.42757 -1.770288 0)
			(layer "B.Fab")
			(effects
				(font
					(size 0.7 0.7)
					(thickness 0.15)
				)
				(justify left bottom mirror)
			)
		)
		(property "Datasheet" "https://product.tdk.com/en/search/capacitor/ceramic/mlcc/info?part_no=C1608X5R1E106M080AC"
			(at 0 0 180)
			(layer "F.Fab")
			(hide yes)
			(effects
				(font
					(size 1.27 1.27)
					(thickness 0.15)
				)
			)
		)
		(property "Description" "SMD Multilayer Ceramic Capacitor, 10 µF, 25 V, 0603 [1608 Metric], ± 20%, X5R, C"
			(at 0 0 180)
			(layer "F.Fab")
			(hide yes)
			(effects
				(font
					(size 1.27 1.27)
					(thickness 0.15)
				)
			)
		)
		(property "MPN" "C1608X5R1E106M080AC"
			(at 0 0 180)
			(unlocked yes)
			(layer "B.Fab")
			(hide yes)
			(effects
				(font
					(size 1 1)
					(thickness 0.15)
				)
				(justify mirror)
			)
		)
		(property "Manufacturer" "TDK"
			(at 0 0 180)
			(unlocked yes)
			(layer "B.Fab")
			(hide yes)
			(effects
				(font
					(size 1 1)
					(thickness 0.15)
				)
				(justify mirror)
			)
		)
		(property "License" "Apache-2.0"
			(at 0 0 180)
			(unlocked yes)
			(layer "B.Fab")
			(hide yes)
			(effects
				(font
					(size 1 1)
					(thickness 0.15)
				)
				(justify mirror)
			)
		)
		(property "Author" "Antmicro"
			(at 0 0 180)
			(unlocked yes)
			(layer "B.Fab")
			(hide yes)
			(effects
				(font
					(size 1 1)
					(thickness 0.15)
				)
				(justify mirror)
			)
		)
		(property "Val" "10u"
			(at 0 0 180)
			(unlocked yes)
			(layer "B.Fab")
			(hide yes)
			(effects
				(font
					(size 1 1)
					(thickness 0.15)
				)
				(justify mirror)
			)
		)
		(property "Voltage" "25V"
			(at 0 0 180)
			(unlocked yes)
			(layer "B.Fab")
			(hide yes)
			(effects
				(font
					(size 1 1)
					(thickness 0.15)
				)
				(justify mirror)
			)
		)
		(property "Dielectric" ""
			(at 0 0 180)
			(unlocked yes)
			(layer "B.Fab")
			(hide yes)
			(effects
				(font
					(size 1 1)
					(thickness 0.15)
				)
				(justify mirror)
			)
		)
		(sheetname "/DC-DC Converters/")
		(sheetfile "dc-dc_converters.kicad_sch")
		(attr smd)
		(fp_line
			(start 0.15 0.4)
			(end -0.15 0.4)
			(stroke
				(width 0.15)
				(type solid)
			)
			(layer "B.SilkS")
		)
		(fp_line
			(start 0.15 -0.4)
			(end -0.15 -0.4)
			(stroke
				(width 0.15)
				(type solid)
			)
			(layer "B.SilkS")
		)
		(fp_rect
			(start -1.25 0.65)
			(end 1.25 -0.65)
			(stroke
				(width 0.05)
				(type solid)
			)
			(fill no)
			(layer "B.CrtYd")
		)
		(fp_rect
			(start -0.8 0.4)
			(end 0.8 -0.4)
			(stroke
				(width 0.15)
				(type solid)
			)
			(fill no)
			(layer "B.Fab")
		)
		(pad "1" smd roundrect
			(at -0.7 0 180)
			(size 0.8 1)
			(layers "B.Cu" "B.Mask" "B.Paste")
			(roundrect_rratio 0.2)
			(net 2 "GND")
			(pintype "passive")
		)
		(pad "2" smd roundrect
			(at 0.7 0 180)
			(size 0.8 1)
			(layers "B.Cu" "B.Mask" "B.Paste")
			(roundrect_rratio 0.2)
			(net 25 "+5V")
			(pintype "passive")
		)
	)
	(footprint "antmicro-footprints:C_0805_2012Metric"
		(layer "B.Cu")
		(at 99.8 93.75 -90)
		(descr "Capacitor SMD 0805")
		(tags "capacitor SMD 0805")
		(property "Reference" "C18"
			(at -1.04 0.867 90)
			(layer "B.SilkS")
			(effects
				(font
					(size 0.7 0.7)
					(thickness 0.15)
				)
				(justify left bottom mirror)
			)
		)
		(property "Value" "C_22u_25V_0805"
			(at -2.055717 -1.963152 90)
			(layer "B.Fab")
			(effects
				(font
					(size 0.7 0.7)
					(thickness 0.15)
				)
				(justify left bottom mirror)
			)
		)
		(property "Datasheet" "https://product.samsungsem.com/mlcc/CL21A226MAYNNN.do"
			(at 0 0 270)
			(layer "F.Fab")
			(hide yes)
			(effects
				(font
					(size 1.27 1.27)
					(thickness 0.15)
				)
			)
		)
		(property "Description" "SMT Multilayer Ceramic Capacitor, 22uF, +/-20%, 25V, X5R, 0805 [2012 Metric]"
			(at 0 0 270)
			(layer "F.Fab")
			(hide yes)
			(effects
				(font
					(size 1.27 1.27)
					(thickness 0.15)
				)
			)
		)
		(property "MPN" "CL21A226MAYNNNE"
			(at 0 0 270)
			(unlocked yes)
			(layer "B.Fab")
			(hide yes)
			(effects
				(font
					(size 1 1)
					(thickness 0.15)
				)
				(justify mirror)
			)
		)
		(property "Manufacturer" "Samsung Electro-Mechanics"
			(at 0 0 270)
			(unlocked yes)
			(layer "B.Fab")
			(hide yes)
			(effects
				(font
					(size 1 1)
					(thickness 0.15)
				)
				(justify mirror)
			)
		)
		(property "License" "Apache-2.0"
			(at 0 0 270)
			(unlocked yes)
			(layer "B.Fab")
			(hide yes)
			(effects
				(font
					(size 1 1)
					(thickness 0.15)
				)
				(justify mirror)
			)
		)
		(property "Author" "Antmicro"
			(at 0 0 270)
			(unlocked yes)
			(layer "B.Fab")
			(hide yes)
			(effects
				(font
					(size 1 1)
					(thickness 0.15)
				)
				(justify mirror)
			)
		)
		(property "Val" "22u"
			(at 0 0 270)
			(unlocked yes)
			(layer "B.Fab")
			(hide yes)
			(effects
				(font
					(size 1 1)
					(thickness 0.15)
				)
				(justify mirror)
			)
		)
		(property "Voltage" "25V"
			(at 0 0 270)
			(unlocked yes)
			(layer "B.Fab")
			(hide yes)
			(effects
				(font
					(size 1 1)
					(thickness 0.15)
				)
				(justify mirror)
			)
		)
		(property "Dielectric" "X5R"
			(at 0 0 270)
			(unlocked yes)
			(layer "B.Fab")
			(hide yes)
			(effects
				(font
					(size 1 1)
					(thickness 0.15)
				)
				(justify mirror)
			)
		)
		(property "Public" "False"
			(at 0 0 270)
			(unlocked yes)
			(layer "B.Fab")
			(hide yes)
			(effects
				(font
					(size 1 1)
					(thickness 0.15)
				)
				(justify mirror)
			)
		)
		(sheetname "/DC-DC Converters/")
		(sheetfile "dc-dc_converters.kicad_sch")
		(attr smd)
		(fp_line
			(start 0.3 0.7)
			(end -0.3 0.7)
			(stroke
				(width 0.15)
				(type solid)
			)
			(layer "B.SilkS")
		)
		(fp_line
			(start 0.3 -0.7)
			(end -0.3 -0.7)
			(stroke
				(width 0.15)
				(type solid)
			)
			(layer "B.SilkS")
		)
		(fp_rect
			(start 1.95 0.9)
			(end -1.95 -0.9)
			(stroke
				(width 0.05)
				(type default)
			)
			(fill no)
			(layer "B.CrtYd")
		)
		(fp_rect
			(start -0.95 0.675)
			(end 0.95 -0.675)
			(stroke
				(width 0.15)
				(type solid)
			)
			(fill no)
			(layer "B.Fab")
		)
		(pad "1" smd roundrect
			(at -1.1 0 270)
			(size 1.2 1.3)
			(layers "B.Cu" "B.Mask" "B.Paste")
			(roundrect_rratio 0.25)
			(net 2 "GND")
			(pintype "passive")
		)
		(pad "2" smd roundrect
			(at 1.1 0 270)
			(size 1.2 1.3)
			(layers "B.Cu" "B.Mask" "B.Paste")
			(roundrect_rratio 0.25)
			(net 5 "+12V")
			(pintype "passive")
		)
	)
	(footprint "antmicro-footprints:C_0805_2012Metric"
		(layer "B.Cu")
		(at 97.95 98.2 90)
		(descr "Capacitor SMD 0805")
		(tags "capacitor SMD 0805")
		(property "Reference" "C39"
			(at 1.807 -0.922 180)
			(layer "B.SilkS")
			(effects
				(font
					(size 0.7 0.7)
					(thickness 0.15)
				)
				(justify right bottom mirror)
			)
		)
		(property "Value" "C_22u_25V_0805"
			(at -2.055717 -1.963152 90)
			(layer "B.Fab")
			(effects
				(font
					(size 0.7 0.7)
					(thickness 0.15)
				)
				(justify right bottom mirror)
			)
		)
		(property "Datasheet" "https://product.samsungsem.com/mlcc/CL21A226MAYNNN.do"
			(at 0 0 90)
			(layer "F.Fab")
			(hide yes)
			(effects
				(font
					(size 1.27 1.27)
					(thickness 0.15)
				)
			)
		)
		(property "Description" "SMT Multilayer Ceramic Capacitor, 22uF, +/-20%, 25V, X5R, 0805 [2012 Metric]"
			(at 0 0 90)
			(layer "F.Fab")
			(hide yes)
			(effects
				(font
					(size 1.27 1.27)
					(thickness 0.15)
				)
			)
		)
		(property "MPN" "CL21A226MAYNNNE"
			(at 0 0 90)
			(unlocked yes)
			(layer "B.Fab")
			(hide yes)
			(effects
				(font
					(size 1 1)
					(thickness 0.15)
				)
				(justify mirror)
			)
		)
		(property "Manufacturer" "Samsung Electro-Mechanics"
			(at 0 0 90)
			(unlocked yes)
			(layer "B.Fab")
			(hide yes)
			(effects
				(font
					(size 1 1)
					(thickness 0.15)
				)
				(justify mirror)
			)
		)
		(property "License" "Apache-2.0"
			(at 0 0 90)
			(unlocked yes)
			(layer "B.Fab")
			(hide yes)
			(effects
				(font
					(size 1 1)
					(thickness 0.15)
				)
				(justify mirror)
			)
		)
		(property "Author" "Antmicro"
			(at 0 0 90)
			(unlocked yes)
			(layer "B.Fab")
			(hide yes)
			(effects
				(font
					(size 1 1)
					(thickness 0.15)
				)
				(justify mirror)
			)
		)
		(property "Val" "22u"
			(at 0 0 90)
			(unlocked yes)
			(layer "B.Fab")
			(hide yes)
			(effects
				(font
					(size 1 1)
					(thickness 0.15)
				)
				(justify mirror)
			)
		)
		(property "Voltage" "25V"
			(at 0 0 90)
			(unlocked yes)
			(layer "B.Fab")
			(hide yes)
			(effects
				(font
					(size 1 1)
					(thickness 0.15)
				)
				(justify mirror)
			)
		)
		(property "Dielectric" "X5R"
			(at 0 0 90)
			(unlocked yes)
			(layer "B.Fab")
			(hide yes)
			(effects
				(font
					(size 1 1)
					(thickness 0.15)
				)
				(justify mirror)
			)
		)
		(property "Public" "False"
			(at 0 0 90)
			(unlocked yes)
			(layer "B.Fab")
			(hide yes)
			(effects
				(font
					(size 1 1)
					(thickness 0.15)
				)
				(justify mirror)
			)
		)
		(sheetname "/DC-DC Converters/")
		(sheetfile "dc-dc_converters.kicad_sch")
		(attr smd)
		(fp_line
			(start 0.3 -0.7)
			(end -0.3 -0.7)
			(stroke
				(width 0.15)
				(type solid)
			)
			(layer "B.SilkS")
		)
		(fp_line
			(start 0.3 0.7)
			(end -0.3 0.7)
			(stroke
				(width 0.15)
				(type solid)
			)
			(layer "B.SilkS")
		)
		(fp_rect
			(start 1.95 0.9)
			(end -1.95 -0.9)
			(stroke
				(width 0.05)
				(type default)
			)
			(fill no)
			(layer "B.CrtYd")
		)
		(fp_rect
			(start -0.95 0.675)
			(end 0.95 -0.675)
			(stroke
				(width 0.15)
				(type solid)
			)
			(fill no)
			(layer "B.Fab")
		)
		(pad "1" smd roundrect
			(at -1.1 0 90)
			(size 1.2 1.3)
			(layers "B.Cu" "B.Mask" "B.Paste")
			(roundrect_rratio 0.25)
			(net 2 "GND")
			(pintype "passive")
		)
		(pad "2" smd roundrect
			(at 1.1 0 90)
			(size 1.2 1.3)
			(layers "B.Cu" "B.Mask" "B.Paste")
			(roundrect_rratio 0.25)
			(net 5 "+12V")
			(pintype "passive")
		)
	)
	(footprint "antmicro-footprints:C_0805_2012Metric"
		(layer "B.Cu")
		(at 88.95 93.05 -90)
		(descr "Capacitor SMD 0805")
		(tags "capacitor SMD 0805")
		(property "Reference" "C17"
			(at -17.231 4.874 180)
			(layer "B.SilkS")
			(effects
				(font
					(size 0.7 0.7)
					(thickness 0.15)
				)
				(justify left bottom mirror)
			)
		)
		(property "Value" "C_22u_25V_0805"
			(at -2.055717 -1.963152 90)
			(layer "B.Fab")
			(effects
				(font
					(size 0.7 0.7)
					(thickness 0.15)
				)
				(justify left bottom mirror)
			)
		)
		(property "Datasheet" "https://product.samsungsem.com/mlcc/CL21A226MAYNNN.do"
			(at 0 0 270)
			(layer "F.Fab")
			(hide yes)
			(effects
				(font
					(size 1.27 1.27)
					(thickness 0.15)
				)
			)
		)
		(property "Description" "SMT Multilayer Ceramic Capacitor, 22uF, +/-20%, 25V, X5R, 0805 [2012 Metric]"
			(at 0 0 270)
			(layer "F.Fab")
			(hide yes)
			(effects
				(font
					(size 1.27 1.27)
					(thickness 0.15)
				)
			)
		)
		(property "MPN" "CL21A226MAYNNNE"
			(at 0 0 270)
			(unlocked yes)
			(layer "B.Fab")
			(hide yes)
			(effects
				(font
					(size 1 1)
					(thickness 0.15)
				)
				(justify mirror)
			)
		)
		(property "Manufacturer" "Samsung Electro-Mechanics"
			(at 0 0 270)
			(unlocked yes)
			(layer "B.Fab")
			(hide yes)
			(effects
				(font
					(size 1 1)
					(thickness 0.15)
				)
				(justify mirror)
			)
		)
		(property "License" "Apache-2.0"
			(at 0 0 270)
			(unlocked yes)
			(layer "B.Fab")
			(hide yes)
			(effects
				(font
					(size 1 1)
					(thickness 0.15)
				)
				(justify mirror)
			)
		)
		(property "Author" "Antmicro"
			(at 0 0 270)
			(unlocked yes)
			(layer "B.Fab")
			(hide yes)
			(effects
				(font
					(size 1 1)
					(thickness 0.15)
				)
				(justify mirror)
			)
		)
		(property "Val" "22u"
			(at 0 0 270)
			(unlocked yes)
			(layer "B.Fab")
			(hide yes)
			(effects
				(font
					(size 1 1)
					(thickness 0.15)
				)
				(justify mirror)
			)
		)
		(property "Voltage" "25V"
			(at 0 0 270)
			(unlocked yes)
			(layer "B.Fab")
			(hide yes)
			(effects
				(font
					(size 1 1)
					(thickness 0.15)
				)
				(justify mirror)
			)
		)
		(property "Dielectric" "X5R"
			(at 0 0 270)
			(unlocked yes)
			(layer "B.Fab")
			(hide yes)
			(effects
				(font
					(size 1 1)
					(thickness 0.15)
				)
				(justify mirror)
			)
		)
		(property "Public" "False"
			(at 0 0 270)
			(unlocked yes)
			(layer "B.Fab")
			(hide yes)
			(effects
				(font
					(size 1 1)
					(thickness 0.15)
				)
				(justify mirror)
			)
		)
		(sheetname "/DC-DC Converters/")
		(sheetfile "dc-dc_converters.kicad_sch")
		(attr smd)
		(fp_line
			(start 0.3 0.7)
			(end -0.3 0.7)
			(stroke
				(width 0.15)
				(type solid)
			)
			(layer "B.SilkS")
		)
		(fp_line
			(start 0.3 -0.7)
			(end -0.3 -0.7)
			(stroke
				(width 0.15)
				(type solid)
			)
			(layer "B.SilkS")
		)
		(fp_rect
			(start 1.95 0.9)
			(end -1.95 -0.9)
			(stroke
				(width 0.05)
				(type default)
			)
			(fill no)
			(layer "B.CrtYd")
		)
		(fp_rect
			(start -0.95 0.675)
			(end 0.95 -0.675)
			(stroke
				(width 0.15)
				(type solid)
			)
			(fill no)
			(layer "B.Fab")
		)
		(pad "1" smd roundrect
			(at -1.1 0 270)
			(size 1.2 1.3)
			(layers "B.Cu" "B.Mask" "B.Paste")
			(roundrect_rratio 0.25)
			(net 2 "GND")
			(pintype "passive")
		)
		(pad "2" smd roundrect
			(at 1.1 0 270)
			(size 1.2 1.3)
			(layers "B.Cu" "B.Mask" "B.Paste")
			(roundrect_rratio 0.25)
			(net 5 "+12V")
			(pintype "passive")
		)
	)
	(footprint "antmicro-footprints:WSON-6-1EP_2x2mm_P0.65mm"
		(layer "B.Cu")
		(at 86.9 66.9)
		(property "Reference" "U8"
			(at -1.175 2.188 0)
			(layer "B.SilkS")
			(effects
				(font
					(size 0.7 0.7)
					(thickness 0.15)
				)
				(justify right bottom mirror)
			)
		)
		(property "Value" "TVS2200DRVR"
			(at 0 -2.2 0)
			(layer "B.Fab")
			(effects
				(font
					(size 0.7 0.7)
					(thickness 0.15)
				)
				(justify right bottom mirror)
			)
		)
		(property "Datasheet" "https://www.ti.com/lit/ds/symlink/tvs2200.pdf?ts=1712230685180&ref_url=https%253A%252F%252Fwww.ti.com%252Fproduct%252FTVS2200"
			(at 0 0 0)
			(layer "F.Fab")
			(hide yes)
			(effects
				(font
					(size 1.27 1.27)
					(thickness 0.15)
				)
			)
		)
		(property "Description" "ESD Protection Device, 1 kV, WSON-6, 22 V, 105 pF"
			(at 0 0 0)
			(layer "F.Fab")
			(hide yes)
			(effects
				(font
					(size 1.27 1.27)
					(thickness 0.15)
				)
			)
		)
		(property "MPN" "TVS2200DRVR"
			(at 0 0 0)
			(unlocked yes)
			(layer "B.Fab")
			(hide yes)
			(effects
				(font
					(size 1 1)
					(thickness 0.15)
				)
				(justify mirror)
			)
		)
		(property "Manufacturer" "Texas Instruments"
			(at 0 0 0)
			(unlocked yes)
			(layer "B.Fab")
			(hide yes)
			(effects
				(font
					(size 1 1)
					(thickness 0.15)
				)
				(justify mirror)
			)
		)
		(property "License" "Apache-2.0"
			(at 0 0 0)
			(unlocked yes)
			(layer "B.Fab")
			(hide yes)
			(effects
				(font
					(size 1 1)
					(thickness 0.15)
				)
				(justify mirror)
			)
		)
		(property "Author" "Antmicro"
			(at 0 0 0)
			(unlocked yes)
			(layer "B.Fab")
			(hide yes)
			(effects
				(font
					(size 1 1)
					(thickness 0.15)
				)
				(justify mirror)
			)
		)
		(sheetname "/USB PD/")
		(sheetfile "usb_pd.kicad_sch")
		(attr smd)
		(fp_line
			(start -1.05 1)
			(end 1 1)
			(stroke
				(width 0.12)
				(type solid)
			)
			(layer "B.SilkS")
		)
		(fp_line
			(start 1 -1)
			(end -1 -1)
			(stroke
				(width 0.12)
				(type solid)
			)
			(layer "B.SilkS")
		)
		(fp_circle
			(center -1.275 1.075)
			(end -1.224 1.075)
			(stroke
				(width 0.15)
				(type solid)
			)
			(fill yes)
			(layer "B.SilkS")
		)
		(fp_rect
			(start -1.45 1.25)
			(end 1.45 -1.25)
			(stroke
				(width 0.05)
				(type solid)
			)
			(fill no)
			(layer "B.CrtYd")
		)
		(pad "1" smd roundrect
			(at -0.975 0.652)
			(size 0.45 0.4)
			(layers "B.Cu" "B.Mask" "B.Paste")
			(roundrect_rratio 0.25)
			(net 2 "GND")
			(pinfunction "GND")
			(pintype "passive")
		)
		(pad "2" smd roundrect
			(at -0.975 0)
			(size 0.45 0.4)
			(layers "B.Cu" "B.Mask" "B.Paste")
			(roundrect_rratio 0.25)
			(net 2 "GND")
			(pinfunction "GND")
			(pintype "passive")
		)
		(pad "3" smd roundrect
			(at -0.975 -0.65)
			(size 0.45 0.4)
			(layers "B.Cu" "B.Mask" "B.Paste")
			(roundrect_rratio 0.25)
			(net 2 "GND")
			(pinfunction "GND")
			(pintype "passive")
		)
		(pad "4" smd roundrect
			(at 0.973 -0.65)
			(size 0.45 0.4)
			(layers "B.Cu" "B.Mask" "B.Paste")
			(roundrect_rratio 0.25)
			(net 33 "/USB PD/CC2")
			(pinfunction "IN")
			(pintype "passive")
		)
		(pad "5" smd roundrect
			(at 0.973 0)
			(size 0.45 0.4)
			(layers "B.Cu" "B.Mask" "B.Paste")
			(roundrect_rratio 0.25)
			(net 33 "/USB PD/CC2")
			(pinfunction "IN")
			(pintype "passive")
		)
		(pad "6" smd roundrect
			(at 0.973 0.652)
			(size 0.45 0.4)
			(layers "B.Cu" "B.Mask" "B.Paste")
			(roundrect_rratio 0.25)
			(net 33 "/USB PD/CC2")
			(pinfunction "IN")
			(pintype "passive")
		)
		(pad "7" smd roundrect
			(at 0 0)
			(size 1.12 1.72)
			(layers "B.Cu" "B.Mask" "B.Paste")
			(roundrect_rratio 0.1)
			(net 2 "GND")
			(pinfunction "GND")
			(pintype "passive")
		)
	)
	(footprint "antmicro-footprints:SOD-123FL"
		(layer "B.Cu")
		(at 83.5 95.7 90)
		(property "Reference" "D5"
			(at -3.65 0.576 0)
			(layer "B.SilkS")
			(effects
				(font
					(size 0.7 0.7)
					(thickness 0.15)
				)
				(justify left bottom mirror)
			)
		)
		(property "Value" "SZSMF4L12AT3G"
			(at 0 -1.967 90)
			(layer "B.Fab")
			(effects
				(font
					(size 0.7 0.7)
					(thickness 0.15)
				)
				(justify right bottom mirror)
			)
		)
		(property "Datasheet" "https://www.mouser.com/datasheet/2/240/media-3320461.pdf"
			(at 0 0 90)
			(layer "F.Fab")
			(hide yes)
			(effects
				(font
					(size 1.27 1.27)
					(thickness 0.15)
				)
			)
		)
		(property "Description" "ESD, TVS Diode, 14V, UNI, 400W, SOD-123FL"
			(at 0 0 90)
			(layer "F.Fab")
			(hide yes)
			(effects
				(font
					(size 1.27 1.27)
					(thickness 0.15)
				)
			)
		)
		(property "MPN" "SZSMF4L12AT3G"
			(at 0 0 90)
			(unlocked yes)
			(layer "B.Fab")
			(hide yes)
			(effects
				(font
					(size 1 1)
					(thickness 0.15)
				)
				(justify mirror)
			)
		)
		(property "Author" "Antmicro"
			(at 0 0 90)
			(unlocked yes)
			(layer "B.Fab")
			(hide yes)
			(effects
				(font
					(size 1 1)
					(thickness 0.15)
				)
				(justify mirror)
			)
		)
		(property "License" "Apache-2.0"
			(at 0 0 90)
			(unlocked yes)
			(layer "B.Fab")
			(hide yes)
			(effects
				(font
					(size 1 1)
					(thickness 0.15)
				)
				(justify mirror)
			)
		)
		(property "Manufacturer" "Littelfuse"
			(at 0 0 90)
			(unlocked yes)
			(layer "B.Fab")
			(hide yes)
			(effects
				(font
					(size 1 1)
					(thickness 0.15)
				)
				(justify mirror)
			)
		)
		(sheetname "/DC-DC Converters/")
		(sheetfile "dc-dc_converters.kicad_sch")
		(attr smd)
		(fp_line
			(start 0 -1.1)
			(end -2.3 -1.1)
			(stroke
				(width 0.15)
				(type solid)
			)
			(layer "B.SilkS")
		)
		(fp_line
			(start -2.3 -1.1)
			(end -2.3 1.1)
			(stroke
				(width 0.15)
				(type solid)
			)
			(layer "B.SilkS")
		)
		(fp_line
			(start -2.3 1.1)
			(end 0 1.1)
			(stroke
				(width 0.15)
				(type solid)
			)
			(layer "B.SilkS")
		)
		(fp_rect
			(start -2.35 1.125)
			(end 2.35 -1.125)
			(stroke
				(width 0.05)
				(type solid)
			)
			(fill no)
			(layer "B.CrtYd")
		)
		(fp_rect
			(start -0.775 0.875)
			(end -0.525 -0.875)
			(stroke
				(width 0.15)
				(type solid)
			)
			(fill yes)
			(layer "B.Fab")
		)
		(fp_rect
			(start -1.825 0.875)
			(end 1.824 -0.873)
			(stroke
				(width 0.15)
				(type solid)
			)
			(fill no)
			(layer "B.Fab")
		)
		(pad "1" smd roundrect
			(at -1.43 0 90)
			(size 1.34 1.8)
			(layers "B.Cu" "B.Mask" "B.Paste")
			(roundrect_rratio 0.14)
			(net 26 "Net-(D5-C)")
			(pinfunction "C")
			(pintype "passive")
		)
		(pad "2" smd roundrect
			(at 1.429 0 90)
			(size 1.34 1.8)
			(layers "B.Cu" "B.Mask" "B.Paste")
			(roundrect_rratio 0.14)
			(net 2 "GND")
			(pinfunction "A")
			(pintype "passive")
		)
	)
	(footprint "antmicro-footprints:C_0805_2012Metric"
		(layer "B.Cu")
		(at 92.55 93.05 -90)
		(descr "Capacitor SMD 0805")
		(tags "capacitor SMD 0805")
		(property "Reference" "C32"
			(at -19.263 8.474 180)
			(layer "B.SilkS")
			(effects
				(font
					(size 0.7 0.7)
					(thickness 0.15)
				)
				(justify left bottom mirror)
			)
		)
		(property "Value" "C_22u_25V_0805"
			(at -2.055717 -1.963152 90)
			(layer "B.Fab")
			(effects
				(font
					(size 0.7 0.7)
					(thickness 0.15)
				)
				(justify left bottom mirror)
			)
		)
		(property "Datasheet" "https://product.samsungsem.com/mlcc/CL21A226MAYNNN.do"
			(at 0 0 270)
			(layer "F.Fab")
			(hide yes)
			(effects
				(font
					(size 1.27 1.27)
					(thickness 0.15)
				)
			)
		)
		(property "Description" "SMT Multilayer Ceramic Capacitor, 22uF, +/-20%, 25V, X5R, 0805 [2012 Metric]"
			(at 0 0 270)
			(layer "F.Fab")
			(hide yes)
			(effects
				(font
					(size 1.27 1.27)
					(thickness 0.15)
				)
			)
		)
		(property "MPN" "CL21A226MAYNNNE"
			(at 0 0 270)
			(unlocked yes)
			(layer "B.Fab")
			(hide yes)
			(effects
				(font
					(size 1 1)
					(thickness 0.15)
				)
				(justify mirror)
			)
		)
		(property "Manufacturer" "Samsung Electro-Mechanics"
			(at 0 0 270)
			(unlocked yes)
			(layer "B.Fab")
			(hide yes)
			(effects
				(font
					(size 1 1)
					(thickness 0.15)
				)
				(justify mirror)
			)
		)
		(property "License" "Apache-2.0"
			(at 0 0 270)
			(unlocked yes)
			(layer "B.Fab")
			(hide yes)
			(effects
				(font
					(size 1 1)
					(thickness 0.15)
				)
				(justify mirror)
			)
		)
		(property "Author" "Antmicro"
			(at 0 0 270)
			(unlocked yes)
			(layer "B.Fab")
			(hide yes)
			(effects
				(font
					(size 1 1)
					(thickness 0.15)
				)
				(justify mirror)
			)
		)
		(property "Val" "22u"
			(at 0 0 270)
			(unlocked yes)
			(layer "B.Fab")
			(hide yes)
			(effects
				(font
					(size 1 1)
					(thickness 0.15)
				)
				(justify mirror)
			)
		)
		(property "Voltage" "25V"
			(at 0 0 270)
			(unlocked yes)
			(layer "B.Fab")
			(hide yes)
			(effects
				(font
					(size 1 1)
					(thickness 0.15)
				)
				(justify mirror)
			)
		)
		(property "Dielectric" "X5R"
			(at 0 0 270)
			(unlocked yes)
			(layer "B.Fab")
			(hide yes)
			(effects
				(font
					(size 1 1)
					(thickness 0.15)
				)
				(justify mirror)
			)
		)
		(property "Public" "False"
			(at 0 0 270)
			(unlocked yes)
			(layer "B.Fab")
			(hide yes)
			(effects
				(font
					(size 1 1)
					(thickness 0.15)
				)
				(justify mirror)
			)
		)
		(sheetname "/DC-DC Converters/")
		(sheetfile "dc-dc_converters.kicad_sch")
		(attr smd)
		(fp_line
			(start 0.3 0.7)
			(end -0.3 0.7)
			(stroke
				(width 0.15)
				(type solid)
			)
			(layer "B.SilkS")
		)
		(fp_line
			(start 0.3 -0.7)
			(end -0.3 -0.7)
			(stroke
				(width 0.15)
				(type solid)
			)
			(layer "B.SilkS")
		)
		(fp_rect
			(start 1.95 0.9)
			(end -1.95 -0.9)
			(stroke
				(width 0.05)
				(type default)
			)
			(fill no)
			(layer "B.CrtYd")
		)
		(fp_rect
			(start -0.95 0.675)
			(end 0.95 -0.675)
			(stroke
				(width 0.15)
				(type solid)
			)
			(fill no)
			(layer "B.Fab")
		)
		(pad "1" smd roundrect
			(at -1.1 0 270)
			(size 1.2 1.3)
			(layers "B.Cu" "B.Mask" "B.Paste")
			(roundrect_rratio 0.25)
			(net 2 "GND")
			(pintype "passive")
		)
		(pad "2" smd roundrect
			(at 1.1 0 270)
			(size 1.2 1.3)
			(layers "B.Cu" "B.Mask" "B.Paste")
			(roundrect_rratio 0.25)
			(net 5 "+12V")
			(pintype "passive")
		)
	)
	(footprint "antmicro-footprints:SOT-563"
		(layer "B.Cu")
		(at 85.8 82.65)
		(property "Reference" "U4"
			(at 2.084 -0.862 0)
			(layer "B.SilkS")
			(effects
				(font
					(size 0.7 0.7)
					(thickness 0.15)
				)
				(justify right bottom mirror)
			)
		)
		(property "Value" "AP62301Z6-7"
			(at 0 -2 0)
			(layer "B.Fab")
			(effects
				(font
					(size 0.7 0.7)
					(thickness 0.15)
				)
				(justify right bottom mirror)
			)
		)
		(property "Datasheet" "https://www.diodes.com/assets/Datasheets/AP62300_AP62301_AP62300T.pdf"
			(at 0 0 0)
			(layer "F.Fab")
			(hide yes)
			(effects
				(font
					(size 1.27 1.27)
					(thickness 0.15)
				)
			)
		)
		(property "Description" "DC-DC Switching Synchronous Buck Regulator, Adjustable, 4.2V-18Vin, 0.8V-7V/3A out, SOT-563-6"
			(at 0 0 0)
			(layer "F.Fab")
			(hide yes)
			(effects
				(font
					(size 1.27 1.27)
					(thickness 0.15)
				)
			)
		)
		(property "MPN" "AP62301Z6-7"
			(at 0 0 0)
			(unlocked yes)
			(layer "B.Fab")
			(hide yes)
			(effects
				(font
					(size 1 1)
					(thickness 0.15)
				)
				(justify mirror)
			)
		)
		(property "Manufacturer" "Diodes Incorporated"
			(at 0 0 0)
			(unlocked yes)
			(layer "B.Fab")
			(hide yes)
			(effects
				(font
					(size 1 1)
					(thickness 0.15)
				)
				(justify mirror)
			)
		)
		(property "Author" "Antmicro"
			(at 0 0 0)
			(unlocked yes)
			(layer "B.Fab")
			(hide yes)
			(effects
				(font
					(size 1 1)
					(thickness 0.15)
				)
				(justify mirror)
			)
		)
		(property "License" "Apache-2.0"
			(at 0 0 0)
			(unlocked yes)
			(layer "B.Fab")
			(hide yes)
			(effects
				(font
					(size 1 1)
					(thickness 0.15)
				)
				(justify mirror)
			)
		)
		(sheetname "/DC-DC Converters/")
		(sheetfile "dc-dc_converters.kicad_sch")
		(attr smd)
		(fp_line
			(start -0.778 -0.949)
			(end -0.778 -0.776)
			(stroke
				(width 0.15)
				(type solid)
			)
			(layer "B.SilkS")
		)
		(fp_line
			(start -0.724 0.778)
			(end -0.499 0.974)
			(stroke
				(width 0.15)
				(type solid)
			)
			(layer "B.SilkS")
		)
		(fp_line
			(start -0.424 -0.949)
			(end -0.778 -0.949)
			(stroke
				(width 0.15)
				(type solid)
			)
			(layer "B.SilkS")
		)
		(fp_line
			(start 0.526 -0.972)
			(end 0.776 -0.972)
			(stroke
				(width 0.15)
				(type solid)
			)
			(layer "B.SilkS")
		)
		(fp_line
			(start 0.526 0.974)
			(end 0.776 0.974)
			(stroke
				(width 0.15)
				(type solid)
			)
			(layer "B.SilkS")
		)
		(fp_line
			(start 0.776 -0.972)
			(end 0.776 -0.776)
			(stroke
				(width 0.15)
				(type solid)
			)
			(layer "B.SilkS")
		)
		(fp_line
			(start 0.776 0.778)
			(end 0.776 0.974)
			(stroke
				(width 0.15)
				(type solid)
			)
			(layer "B.SilkS")
		)
		(fp_circle
			(center -0.903 0.999)
			(end -0.952 0.95)
			(stroke
				(width 0.15)
				(type solid)
			)
			(fill yes)
			(layer "B.SilkS")
		)
		(fp_rect
			(start 1.19 1.12)
			(end -1.2 -1.1)
			(stroke
				(width 0.05)
				(type solid)
			)
			(fill no)
			(layer "B.CrtYd")
		)
		(fp_line
			(start -0.653 -0.847)
			(end -0.653 0.678)
			(stroke
				(width 0.15)
				(type solid)
			)
			(layer "B.Fab")
		)
		(fp_line
			(start -0.653 -0.847)
			(end 0.651 -0.847)
			(stroke
				(width 0.15)
				(type solid)
			)
			(layer "B.Fab")
		)
		(fp_line
			(start -0.653 0.678)
			(end -0.453 0.849)
			(stroke
				(width 0.15)
				(type solid)
			)
			(layer "B.Fab")
		)
		(fp_line
			(start 0.651 -0.847)
			(end 0.651 0.849)
			(stroke
				(width 0.15)
				(type solid)
			)
			(layer "B.Fab")
		)
		(fp_line
			(start 0.651 0.849)
			(end -0.453 0.849)
			(stroke
				(width 0.15)
				(type solid)
			)
			(layer "B.Fab")
		)
		(pad "1" smd roundrect
			(at -0.749 0.499 90)
			(size 0.3 0.6)
			(layers "B.Cu" "B.Mask" "B.Paste")
			(roundrect_rratio 0.25)
			(net 5 "+12V")
			(pinfunction "V_{IN}")
			(pintype "power_in")
		)
		(pad "2" smd roundrect
			(at -0.749 -0.001 90)
			(size 0.3 0.6)
			(layers "B.Cu" "B.Mask" "B.Paste")
			(roundrect_rratio 0.25)
			(net 23 "Net-(U4-SW)")
			(pinfunction "SW")
			(pintype "power_out")
		)
		(pad "3" smd roundrect
			(at -0.749 -0.497 90)
			(size 0.3 0.6)
			(layers "B.Cu" "B.Mask" "B.Paste")
			(roundrect_rratio 0.25)
			(net 2 "GND")
			(pinfunction "GND")
			(pintype "power_in")
		)
		(pad "4" smd roundrect
			(at 0.747 -0.497 90)
			(size 0.3 0.6)
			(layers "B.Cu" "B.Mask" "B.Paste")
			(roundrect_rratio 0.25)
			(net 24 "Net-(U4-BST)")
			(pinfunction "BST")
			(pintype "output")
		)
		(pad "5" smd roundrect
			(at 0.747 -0.001 90)
			(size 0.3 0.6)
			(layers "B.Cu" "B.Mask" "B.Paste")
			(roundrect_rratio 0.25)
			(net 9 "Net-(U4-EN)")
			(pinfunction "EN")
			(pintype "input")
		)
		(pad "6" smd roundrect
			(at 0.747 0.499 90)
			(size 0.3 0.6)
			(layers "B.Cu" "B.Mask" "B.Paste")
			(roundrect_rratio 0.25)
			(net 39 "Net-(U4-FB)")
			(pinfunction "FB")
			(pintype "input")
		)
	)
	(footprint "antmicro-footprints:D_0402_1005Metric"
		(layer "B.Cu")
		(at 97.6 93.45 -90)
		(property "Reference" "D2"
			(at -2.45 -0.426 270)
			(layer "B.SilkS")
			(effects
				(font
					(size 0.7 0.7)
					(thickness 0.15)
				)
				(justify left bottom mirror)
			)
		)
		(property "Value" "AXGD10402KR"
			(at -2.54 -2.54 90)
			(layer "B.Fab")
			(effects
				(font
					(size 0.7 0.7)
					(thickness 0.15)
				)
				(justify left bottom mirror)
			)
		)
		(property "Datasheet" "https://www.littelfuse.com/media?resourcetype=datasheets&itemid=020b2bf2-064c-4ff1-a898-b4ec805b2fea&filename=littelfuse-xtremeguard-axgd-datasheet"
			(at 0 0 270)
			(layer "F.Fab")
			(hide yes)
			(effects
				(font
					(size 1.27 1.27)
					(thickness 0.15)
				)
			)
		)
		(property "Description" "Bidirectional TVS, 30 kV,  0402, 24 V, 0.04 pF"
			(at 0 0 270)
			(layer "F.Fab")
			(hide yes)
			(effects
				(font
					(size 1.27 1.27)
					(thickness 0.15)
				)
			)
		)
		(property "Manufacturer" "Littelfuse"
			(at 0 0 270)
			(unlocked yes)
			(layer "B.Fab")
			(hide yes)
			(effects
				(font
					(size 1 1)
					(thickness 0.15)
				)
				(justify mirror)
			)
		)
		(property "MPN" "AXGD10402KR"
			(at 0 0 270)
			(unlocked yes)
			(layer "B.Fab")
			(hide yes)
			(effects
				(font
					(size 1 1)
					(thickness 0.15)
				)
				(justify mirror)
			)
		)
		(property "Author" "Antmicro"
			(at 0 0 270)
			(unlocked yes)
			(layer "B.Fab")
			(hide yes)
			(effects
				(font
					(size 1 1)
					(thickness 0.15)
				)
				(justify mirror)
			)
		)
		(property "License" "Apache-2.0"
			(at 0 0 270)
			(unlocked yes)
			(layer "B.Fab")
			(hide yes)
			(effects
				(font
					(size 1 1)
					(thickness 0.15)
				)
				(justify mirror)
			)
		)
		(sheetname "/DC-DC Converters/")
		(sheetfile "dc-dc_converters.kicad_sch")
		(attr smd)
		(fp_line
			(start -0.1 0.255)
			(end 0.1 0.255)
			(stroke
				(width 0.15)
				(type solid)
			)
			(layer "B.SilkS")
		)
		(fp_line
			(start -0.875 -0.25)
			(end -0.875 0.25)
			(stroke
				(width 0.15)
				(type solid)
			)
			(layer "B.SilkS")
		)
		(fp_line
			(start 0.1 -0.255)
			(end -0.1 -0.255)
			(stroke
				(width 0.15)
				(type solid)
			)
			(layer "B.SilkS")
		)
		(fp_rect
			(start -0.925 0.47)
			(end 0.925 -0.47)
			(stroke
				(width 0.05)
				(type default)
			)
			(fill no)
			(layer "B.CrtYd")
		)
		(fp_line
			(start -0.51 0.255)
			(end -0.51 -0.255)
			(stroke
				(width 0.15)
				(type solid)
			)
			(layer "B.Fab")
		)
		(fp_line
			(start 0.51 0.255)
			(end -0.51 0.255)
			(stroke
				(width 0.15)
				(type solid)
			)
			(layer "B.Fab")
		)
		(fp_line
			(start -0.5 -0.05)
			(end -0.2 0.25)
			(stroke
				(width 0.15)
				(type solid)
			)
			(layer "B.Fab")
		)
		(fp_line
			(start -0.51 -0.255)
			(end 0.51 -0.255)
			(stroke
				(width 0.15)
				(type solid)
			)
			(layer "B.Fab")
		)
		(fp_line
			(start 0.51 -0.255)
			(end 0.51 0.255)
			(stroke
				(width 0.15)
				(type solid)
			)
			(layer "B.Fab")
		)
		(pad "1" smd roundrect
			(at -0.48 0 270)
			(size 0.59 0.64)
			(layers "B.Cu" "B.Mask" "B.Paste")
			(roundrect_rratio 0.25)
			(net 2 "GND")
			(pinfunction "C")
			(pintype "passive")
		)
		(pad "2" smd roundrect
			(at 0.48 0 270)
			(size 0.59 0.64)
			(layers "B.Cu" "B.Mask" "B.Paste")
			(roundrect_rratio 0.25)
			(net 5 "+12V")
			(pinfunction "A")
			(pintype "passive")
		)
	)
	(footprint "antmicro-footprints:C_1206_3216Metric"
		(layer "B.Cu")
		(at 93.5 97.85 90)
		(descr "Capacitor SMD 1206")
		(tags "capacitor SMD 1206")
		(property "Reference" "C31"
			(at 24.698 -7.138 180)
			(layer "B.SilkS")
			(effects
				(font
					(size 0.7 0.7)
					(thickness 0.15)
				)
				(justify left bottom mirror)
			)
		)
		(property "Value" "C_47u_25V_1206"
			(at 0 -2.101 90)
			(layer "B.Fab")
			(effects
				(font
					(size 0.7 0.7)
					(thickness 0.15)
				)
				(justify right bottom mirror)
			)
		)
		(property "Datasheet" "https://product.tdk.com/en/search/capacitor/ceramic/mlcc/info?part_no=C3216X5R1E476M160AC"
			(at 0 0 90)
			(layer "F.Fab")
			(hide yes)
			(effects
				(font
					(size 1.27 1.27)
					(thickness 0.15)
				)
			)
		)
		(property "Description" "SMD Multilayer Ceramic Capacitor, 47 µF, 25 V, 1206 [3216 Metric], ± 20%, X5R"
			(at 0 0 90)
			(layer "F.Fab")
			(hide yes)
			(effects
				(font
					(size 1.27 1.27)
					(thickness 0.15)
				)
			)
		)
		(property "MPN" "C3216X5R1E476M160AC"
			(at 0 0 90)
			(unlocked yes)
			(layer "B.Fab")
			(hide yes)
			(effects
				(font
					(size 1 1)
					(thickness 0.15)
				)
				(justify mirror)
			)
		)
		(property "Val" "47u"
			(at 0 0 90)
			(unlocked yes)
			(layer "B.Fab")
			(hide yes)
			(effects
				(font
					(size 1 1)
					(thickness 0.15)
				)
				(justify mirror)
			)
		)
		(property "Voltage" "25V"
			(at 0 0 90)
			(unlocked yes)
			(layer "B.Fab")
			(hide yes)
			(effects
				(font
					(size 1 1)
					(thickness 0.15)
				)
				(justify mirror)
			)
		)
		(property "Author" "Antmicro"
			(at 0 0 90)
			(unlocked yes)
			(layer "B.Fab")
			(hide yes)
			(effects
				(font
					(size 1 1)
					(thickness 0.15)
				)
				(justify mirror)
			)
		)
		(property "License" "Apache-2.0"
			(at 0 0 90)
			(unlocked yes)
			(layer "B.Fab")
			(hide yes)
			(effects
				(font
					(size 1 1)
					(thickness 0.15)
				)
				(justify mirror)
			)
		)
		(property "Manufacturer" "TDK"
			(at 0 0 90)
			(unlocked yes)
			(layer "B.Fab")
			(hide yes)
			(effects
				(font
					(size 1 1)
					(thickness 0.15)
				)
				(justify mirror)
			)
		)
		(property "Dielectric" "X5R"
			(at 0 0 90)
			(unlocked yes)
			(layer "B.Fab")
			(hide yes)
			(effects
				(font
					(size 1 1)
					(thickness 0.15)
				)
				(justify mirror)
			)
		)
		(property "Public" "False"
			(at 0 0 90)
			(unlocked yes)
			(layer "B.Fab")
			(hide yes)
			(effects
				(font
					(size 1 1)
					(thickness 0.15)
				)
				(justify mirror)
			)
		)
		(sheetname "/DC-DC Converters/")
		(sheetfile "dc-dc_converters.kicad_sch")
		(attr smd)
		(fp_line
			(start -0.8 -0.901)
			(end 0.8 -0.901)
			(stroke
				(width 0.15)
				(type solid)
			)
			(layer "B.SilkS")
		)
		(fp_line
			(start -0.8 0.899)
			(end 0.8 0.899)
			(stroke
				(width 0.15)
				(type solid)
			)
			(layer "B.SilkS")
		)
		(fp_rect
			(start -2.325 1.15)
			(end 2.325 -1.15)
			(stroke
				(width 0.05)
				(type default)
			)
			(fill no)
			(layer "B.CrtYd")
		)
		(fp_rect
			(start -1.6 0.799)
			(end 1.6 -0.801)
			(stroke
				(width 0.15)
				(type solid)
			)
			(fill no)
			(layer "B.Fab")
		)
		(pad "1" smd roundrect
			(at -1.5 -0.001 90)
			(size 1.15 1.8)
			(layers "B.Cu" "B.Mask" "B.Paste")
			(roundrect_rratio 0.25)
			(net 2 "GND")
			(pintype "passive")
		)
		(pad "2" smd roundrect
			(at 1.5 -0.001 90)
			(size 1.15 1.8)
			(layers "B.Cu" "B.Mask" "B.Paste")
			(roundrect_rratio 0.25)
			(net 5 "+12V")
			(pintype "passive")
		)
	)
	(footprint "antmicro-footprints:WSON-6-1EP_2x2mm_P0.65mm"
		(layer "B.Cu")
		(at 83.9 66.9)
		(property "Reference" "U7"
			(at -1.223 2.188 0)
			(layer "B.SilkS")
			(effects
				(font
					(size 0.7 0.7)
					(thickness 0.15)
				)
				(justify right bottom mirror)
			)
		)
		(property "Value" "TVS2200DRVR"
			(at 0 -2.2 0)
			(layer "B.Fab")
			(effects
				(font
					(size 0.7 0.7)
					(thickness 0.15)
				)
				(justify right bottom mirror)
			)
		)
		(property "Datasheet" "https://www.ti.com/lit/ds/symlink/tvs2200.pdf?ts=1712230685180&ref_url=https%253A%252F%252Fwww.ti.com%252Fproduct%252FTVS2200"
			(at 0 0 0)
			(layer "F.Fab")
			(hide yes)
			(effects
				(font
					(size 1.27 1.27)
					(thickness 0.15)
				)
			)
		)
		(property "Description" "ESD Protection Device, 1 kV, WSON-6, 22 V, 105 pF"
			(at 0 0 0)
			(layer "F.Fab")
			(hide yes)
			(effects
				(font
					(size 1.27 1.27)
					(thickness 0.15)
				)
			)
		)
		(property "MPN" "TVS2200DRVR"
			(at 0 0 0)
			(unlocked yes)
			(layer "B.Fab")
			(hide yes)
			(effects
				(font
					(size 1 1)
					(thickness 0.15)
				)
				(justify mirror)
			)
		)
		(property "Manufacturer" "Texas Instruments"
			(at 0 0 0)
			(unlocked yes)
			(layer "B.Fab")
			(hide yes)
			(effects
				(font
					(size 1 1)
					(thickness 0.15)
				)
				(justify mirror)
			)
		)
		(property "License" "Apache-2.0"
			(at 0 0 0)
			(unlocked yes)
			(layer "B.Fab")
			(hide yes)
			(effects
				(font
					(size 1 1)
					(thickness 0.15)
				)
				(justify mirror)
			)
		)
		(property "Author" "Antmicro"
			(at 0 0 0)
			(unlocked yes)
			(layer "B.Fab")
			(hide yes)
			(effects
				(font
					(size 1 1)
					(thickness 0.15)
				)
				(justify mirror)
			)
		)
		(sheetname "/USB PD/")
		(sheetfile "usb_pd.kicad_sch")
		(attr smd)
		(fp_line
			(start -1.05 1)
			(end 1 1)
			(stroke
				(width 0.12)
				(type solid)
			)
			(layer "B.SilkS")
		)
		(fp_line
			(start 1 -1)
			(end -1 -1)
			(stroke
				(width 0.12)
				(type solid)
			)
			(layer "B.SilkS")
		)
		(fp_circle
			(center -1.275 1.075)
			(end -1.224 1.075)
			(stroke
				(width 0.15)
				(type solid)
			)
			(fill yes)
			(layer "B.SilkS")
		)
		(fp_rect
			(start -1.45 1.25)
			(end 1.45 -1.25)
			(stroke
				(width 0.05)
				(type solid)
			)
			(fill no)
			(layer "B.CrtYd")
		)
		(pad "1" smd roundrect
			(at -0.975 0.652)
			(size 0.45 0.4)
			(layers "B.Cu" "B.Mask" "B.Paste")
			(roundrect_rratio 0.25)
			(net 2 "GND")
			(pinfunction "GND")
			(pintype "passive")
		)
		(pad "2" smd roundrect
			(at -0.975 0)
			(size 0.45 0.4)
			(layers "B.Cu" "B.Mask" "B.Paste")
			(roundrect_rratio 0.25)
			(net 2 "GND")
			(pinfunction "GND")
			(pintype "passive")
		)
		(pad "3" smd roundrect
			(at -0.975 -0.65)
			(size 0.45 0.4)
			(layers "B.Cu" "B.Mask" "B.Paste")
			(roundrect_rratio 0.25)
			(net 2 "GND")
			(pinfunction "GND")
			(pintype "passive")
		)
		(pad "4" smd roundrect
			(at 0.973 -0.65)
			(size 0.45 0.4)
			(layers "B.Cu" "B.Mask" "B.Paste")
			(roundrect_rratio 0.25)
			(net 29 "/USB PD/CC1")
			(pinfunction "IN")
			(pintype "passive")
		)
		(pad "5" smd roundrect
			(at 0.973 0)
			(size 0.45 0.4)
			(layers "B.Cu" "B.Mask" "B.Paste")
			(roundrect_rratio 0.25)
			(net 29 "/USB PD/CC1")
			(pinfunction "IN")
			(pintype "passive")
		)
		(pad "6" smd roundrect
			(at 0.973 0.652)
			(size 0.45 0.4)
			(layers "B.Cu" "B.Mask" "B.Paste")
			(roundrect_rratio 0.25)
			(net 29 "/USB PD/CC1")
			(pinfunction "IN")
			(pintype "passive")
		)
		(pad "7" smd roundrect
			(at 0 0)
			(size 1.12 1.72)
			(layers "B.Cu" "B.Mask" "B.Paste")
			(roundrect_rratio 0.1)
			(net 2 "GND")
			(pinfunction "GND")
			(pintype "passive")
		)
	)
	(footprint "antmicro-footprints:C_0402_1005Metric"
		(layer "B.Cu")
		(at 86.451 86.7 -90)
		(descr "Capacitor SMD 0402")
		(tags "capacitor SMD 0402")
		(property "Reference" "C23"
			(at -1.083 -3.11 90)
			(layer "B.SilkS")
			(effects
				(font
					(size 0.7 0.7)
					(thickness 0.15)
				)
				(justify left bottom mirror)
			)
		)
		(property "Value" "C_100n_50V_X8L_0402"
			(at -1.022927 -2.155213 90)
			(layer "B.Fab")
			(effects
				(font
					(size 0.7 0.7)
					(thickness 0.15)
				)
				(justify left bottom mirror)
			)
		)
		(property "Datasheet" "https://www.murata.com/products/productdetail?partno=GCM155L8EH104KE07%23"
			(at 0 0 270)
			(layer "F.Fab")
			(hide yes)
			(effects
				(font
					(size 1.27 1.27)
					(thickness 0.15)
				)
			)
		)
		(property "Description" "SMD Multilayer Ceramic Capacitor, 100nF, 50V, 0402, ±10%, X8L"
			(at 0 0 270)
			(layer "F.Fab")
			(hide yes)
			(effects
				(font
					(size 1.27 1.27)
					(thickness 0.15)
				)
			)
		)
		(property "MPN" "GCM155L8EH104KE07D"
			(at 0 0 270)
			(unlocked yes)
			(layer "B.Fab")
			(hide yes)
			(effects
				(font
					(size 1 1)
					(thickness 0.15)
				)
				(justify mirror)
			)
		)
		(property "Val" "100n"
			(at 0 0 270)
			(unlocked yes)
			(layer "B.Fab")
			(hide yes)
			(effects
				(font
					(size 1 1)
					(thickness 0.15)
				)
				(justify mirror)
			)
		)
		(property "Voltage" "50V"
			(at 0 0 270)
			(unlocked yes)
			(layer "B.Fab")
			(hide yes)
			(effects
				(font
					(size 1 1)
					(thickness 0.15)
				)
				(justify mirror)
			)
		)
		(property "Dielectric" "X8L"
			(at 0 0 270)
			(unlocked yes)
			(layer "B.Fab")
			(hide yes)
			(effects
				(font
					(size 1 1)
					(thickness 0.15)
				)
				(justify mirror)
			)
		)
		(property "Manufacturer" "Murata"
			(at 0 0 270)
			(unlocked yes)
			(layer "B.Fab")
			(hide yes)
			(effects
				(font
					(size 1 1)
					(thickness 0.15)
				)
				(justify mirror)
			)
		)
		(property "License" "Apache-2.0"
			(at 0 0 270)
			(unlocked yes)
			(layer "B.Fab")
			(hide yes)
			(effects
				(font
					(size 1 1)
					(thickness 0.15)
				)
				(justify mirror)
			)
		)
		(property "Author" "Antmicro"
			(at 0 0 270)
			(unlocked yes)
			(layer "B.Fab")
			(hide yes)
			(effects
				(font
					(size 1 1)
					(thickness 0.15)
				)
				(justify mirror)
			)
		)
		(sheetname "/DC-DC Converters/")
		(sheetfile "dc-dc_converters.kicad_sch")
		(attr smd)
		(fp_rect
			(start -0.925 0.47)
			(end 0.925 -0.47)
			(stroke
				(width 0.05)
				(type default)
			)
			(fill no)
			(layer "B.CrtYd")
		)
		(fp_line
			(start -0.494 0.25)
			(end -0.494 -0.248)
			(stroke
				(width 0.15)
				(type solid)
			)
			(layer "B.Fab")
		)
		(fp_line
			(start 0.504 0.25)
			(end -0.494 0.25)
			(stroke
				(width 0.15)
				(type solid)
			)
			(layer "B.Fab")
		)
		(fp_line
			(start -0.494 -0.248)
			(end 0.504 -0.248)
			(stroke
				(width 0.15)
				(type solid)
			)
			(layer "B.Fab")
		)
		(fp_line
			(start 0.504 -0.248)
			(end 0.504 0.25)
			(stroke
				(width 0.15)
				(type solid)
			)
			(layer "B.Fab")
		)
		(pad "1" smd roundrect
			(at -0.48 0 270)
			(size 0.59 0.64)
			(layers "B.Cu" "B.Mask" "B.Paste")
			(roundrect_rratio 0.25)
			(net 21 "Net-(U3-SW)")
			(pintype "passive")
		)
		(pad "2" smd roundrect
			(at 0.48 0 270)
			(size 0.59 0.64)
			(layers "B.Cu" "B.Mask" "B.Paste")
			(roundrect_rratio 0.25)
			(net 22 "Net-(U3-BST)")
			(pintype "passive")
		)
	)
	(footprint "antmicro-footprints:R_0402_1005Metric"
		(layer "B.Cu")
		(at 87.625 82.9 90)
		(descr "Resistor SMD 0402")
		(tags "resistor SMD 0402")
		(property "Reference" "R1"
			(at 1.0612 2.374 270)
			(layer "B.SilkS")
			(effects
				(font
					(size 0.7 0.7)
					(thickness 0.15)
				)
				(justify left bottom mirror)
			)
		)
		(property "Value" "R_3k16_0402"
			(at -1.011843 -1.772047 90)
			(layer "B.Fab")
			(effects
				(font
					(size 0.7 0.7)
					(thickness 0.15)
				)
				(justify right bottom mirror)
			)
		)
		(property "Datasheet" "https://www.mouser.com/datasheet/2/447/YAGEO_PYu_RC_Group_51_RoHS_L_12-3313492.pdf"
			(at 0 0 90)
			(layer "F.Fab")
			(hide yes)
			(effects
				(font
					(size 1.27 1.27)
					(thickness 0.15)
				)
			)
		)
		(property "Description" "SMD Chip Resistor, 3.16 kohm, ± 1%, 62.5 mW, 0402 [1005 Metric], Thick Film, General Purpose"
			(at 0 0 90)
			(layer "F.Fab")
			(hide yes)
			(effects
				(font
					(size 1.27 1.27)
					(thickness 0.15)
				)
			)
		)
		(property "MPN" "RC0402FR-073K16L"
			(at 0 0 90)
			(unlocked yes)
			(layer "B.Fab")
			(hide yes)
			(effects
				(font
					(size 1 1)
					(thickness 0.15)
				)
				(justify mirror)
			)
		)
		(property "Val" "3k16"
			(at 0 0 90)
			(unlocked yes)
			(layer "B.Fab")
			(hide yes)
			(effects
				(font
					(size 1 1)
					(thickness 0.15)
				)
				(justify mirror)
			)
		)
		(property "License" "Apache-2.0"
			(at 0 0 90)
			(unlocked yes)
			(layer "B.Fab")
			(hide yes)
			(effects
				(font
					(size 1 1)
					(thickness 0.15)
				)
				(justify mirror)
			)
		)
		(property "Manufacturer" "YAGEO"
			(at 0 0 90)
			(unlocked yes)
			(layer "B.Fab")
			(hide yes)
			(effects
				(font
					(size 1 1)
					(thickness 0.15)
				)
				(justify mirror)
			)
		)
		(property "Tolerance" "1%"
			(at 0 0 90)
			(unlocked yes)
			(layer "B.Fab")
			(hide yes)
			(effects
				(font
					(size 1 1)
					(thickness 0.15)
				)
				(justify mirror)
			)
		)
		(property "Author" "Antmicro"
			(at 0 0 90)
			(unlocked yes)
			(layer "B.Fab")
			(hide yes)
			(effects
				(font
					(size 1 1)
					(thickness 0.15)
				)
				(justify mirror)
			)
		)
		(sheetname "/DC-DC Converters/")
		(sheetfile "dc-dc_converters.kicad_sch")
		(attr smd)
		(fp_rect
			(start -0.925 0.47)
			(end 0.925 -0.47)
			(stroke
				(width 0.05)
				(type default)
			)
			(fill no)
			(layer "B.CrtYd")
		)
		(fp_rect
			(start -0.5 0.25)
			(end 0.5 -0.25)
			(stroke
				(width 0.15)
				(type solid)
			)
			(fill no)
			(layer "B.Fab")
		)
		(pad "1" smd roundrect
			(at -0.48 0 90)
			(size 0.59 0.64)
			(layers "B.Cu" "B.Mask" "B.Paste")
			(roundrect_rratio 0.25)
			(net 39 "Net-(U4-FB)")
			(pintype "passive")
		)
		(pad "2" smd roundrect
			(at 0.48 0 90)
			(size 0.59 0.64)
			(layers "B.Cu" "B.Mask" "B.Paste")
			(roundrect_rratio 0.25)
			(net 1 "+3V3")
			(pintype "passive")
		)
	)
	(footprint "antmicro-footprints:R_0402_1005Metric"
		(layer "B.Cu")
		(at 88.575 82.9 -90)
		(descr "Resistor SMD 0402")
		(tags "resistor SMD 0402")
		(property "Reference" "R27"
			(at -1.0612 -2.39 90)
			(layer "B.SilkS")
			(effects
				(font
					(size 0.7 0.7)
					(thickness 0.15)
				)
				(justify left bottom mirror)
			)
		)
		(property "Value" "R_1k_0402"
			(at -1.011843 -1.772047 90)
			(layer "B.Fab")
			(effects
				(font
					(size 0.7 0.7)
					(thickness 0.15)
				)
				(justify left bottom mirror)
			)
		)
		(property "Datasheet" "https://www.bourns.com/docs/product-datasheets/cr.pdf"
			(at 0 0 270)
			(layer "F.Fab")
			(hide yes)
			(effects
				(font
					(size 1.27 1.27)
					(thickness 0.15)
				)
			)
		)
		(property "Description" "SMD Chip Resistor, 1 kohm, ± 1%, 63 mW, 0402 [1005 Metric], Thick Film, General Purpose"
			(at 0 0 270)
			(layer "F.Fab")
			(hide yes)
			(effects
				(font
					(size 1.27 1.27)
					(thickness 0.15)
				)
			)
		)
		(property "MPN" "CR0402-FX-1001GLF"
			(at 0 0 270)
			(unlocked yes)
			(layer "B.Fab")
			(hide yes)
			(effects
				(font
					(size 1 1)
					(thickness 0.15)
				)
				(justify mirror)
			)
		)
		(property "Manufacturer" "Bourns"
			(at 0 0 270)
			(unlocked yes)
			(layer "B.Fab")
			(hide yes)
			(effects
				(font
					(size 1 1)
					(thickness 0.15)
				)
				(justify mirror)
			)
		)
		(property "License" "Apache-2.0"
			(at 0 0 270)
			(unlocked yes)
			(layer "B.Fab")
			(hide yes)
			(effects
				(font
					(size 1 1)
					(thickness 0.15)
				)
				(justify mirror)
			)
		)
		(property "Author" "Antmicro"
			(at 0 0 270)
			(unlocked yes)
			(layer "B.Fab")
			(hide yes)
			(effects
				(font
					(size 1 1)
					(thickness 0.15)
				)
				(justify mirror)
			)
		)
		(property "Val" "1k"
			(at 0 0 270)
			(unlocked yes)
			(layer "B.Fab")
			(hide yes)
			(effects
				(font
					(size 1 1)
					(thickness 0.15)
				)
				(justify mirror)
			)
		)
		(property "Tolerance" "1%"
			(at 0 0 270)
			(unlocked yes)
			(layer "B.Fab")
			(hide yes)
			(effects
				(font
					(size 1 1)
					(thickness 0.15)
				)
				(justify mirror)
			)
		)
		(sheetname "/DC-DC Converters/")
		(sheetfile "dc-dc_converters.kicad_sch")
		(attr smd)
		(fp_rect
			(start -0.925 0.47)
			(end 0.925 -0.47)
			(stroke
				(width 0.05)
				(type default)
			)
			(fill no)
			(layer "B.CrtYd")
		)
		(fp_rect
			(start -0.5 0.25)
			(end 0.5 -0.25)
			(stroke
				(width 0.15)
				(type solid)
			)
			(fill no)
			(layer "B.Fab")
		)
		(pad "1" smd roundrect
			(at -0.48 0 270)
			(size 0.59 0.64)
			(layers "B.Cu" "B.Mask" "B.Paste")
			(roundrect_rratio 0.25)
			(net 2 "GND")
			(pintype "passive")
		)
		(pad "2" smd roundrect
			(at 0.48 0 270)
			(size 0.59 0.64)
			(layers "B.Cu" "B.Mask" "B.Paste")
			(roundrect_rratio 0.25)
			(net 39 "Net-(U4-FB)")
			(pintype "passive")
		)
	)
	(footprint "antmicro-footprints:SOT-563"
		(layer "B.Cu")
		(at 85.801 88.9)
		(property "Reference" "U3"
			(at 3.199 2.075 0)
			(layer "B.SilkS")
			(effects
				(font
					(size 0.7 0.7)
					(thickness 0.15)
				)
				(justify right bottom mirror)
			)
		)
		(property "Value" "AP62301Z6-7"
			(at 0 -2 0)
			(layer "B.Fab")
			(effects
				(font
					(size 0.7 0.7)
					(thickness 0.15)
				)
				(justify right bottom mirror)
			)
		)
		(property "Datasheet" "https://www.diodes.com/assets/Datasheets/AP62300_AP62301_AP62300T.pdf"
			(at 0 0 0)
			(layer "F.Fab")
			(hide yes)
			(effects
				(font
					(size 1.27 1.27)
					(thickness 0.15)
				)
			)
		)
		(property "Description" "DC-DC Switching Synchronous Buck Regulator, Adjustable, 4.2V-18Vin, 0.8V-7V/3A out, SOT-563-6"
			(at 0 0 0)
			(layer "F.Fab")
			(hide yes)
			(effects
				(font
					(size 1.27 1.27)
					(thickness 0.15)
				)
			)
		)
		(property "MPN" "AP62301Z6-7"
			(at 0 0 0)
			(unlocked yes)
			(layer "B.Fab")
			(hide yes)
			(effects
				(font
					(size 1 1)
					(thickness 0.15)
				)
				(justify mirror)
			)
		)
		(property "Manufacturer" "Diodes Incorporated"
			(at 0 0 0)
			(unlocked yes)
			(layer "B.Fab")
			(hide yes)
			(effects
				(font
					(size 1 1)
					(thickness 0.15)
				)
				(justify mirror)
			)
		)
		(property "Author" "Antmicro"
			(at 0 0 0)
			(unlocked yes)
			(layer "B.Fab")
			(hide yes)
			(effects
				(font
					(size 1 1)
					(thickness 0.15)
				)
				(justify mirror)
			)
		)
		(property "License" "Apache-2.0"
			(at 0 0 0)
			(unlocked yes)
			(layer "B.Fab")
			(hide yes)
			(effects
				(font
					(size 1 1)
					(thickness 0.15)
				)
				(justify mirror)
			)
		)
		(sheetname "/DC-DC Converters/")
		(sheetfile "dc-dc_converters.kicad_sch")
		(attr smd)
		(fp_line
			(start -0.778 -0.949)
			(end -0.778 -0.776)
			(stroke
				(width 0.15)
				(type solid)
			)
			(layer "B.SilkS")
		)
		(fp_line
			(start -0.724 0.778)
			(end -0.499 0.974)
			(stroke
				(width 0.15)
				(type solid)
			)
			(layer "B.SilkS")
		)
		(fp_line
			(start -0.424 -0.949)
			(end -0.778 -0.949)
			(stroke
				(width 0.15)
				(type solid)
			)
			(layer "B.SilkS")
		)
		(fp_line
			(start 0.526 -0.972)
			(end 0.776 -0.972)
			(stroke
				(width 0.15)
				(type solid)
			)
			(layer "B.SilkS")
		)
		(fp_line
			(start 0.526 0.974)
			(end 0.776 0.974)
			(stroke
				(width 0.15)
				(type solid)
			)
			(layer "B.SilkS")
		)
		(fp_line
			(start 0.776 -0.972)
			(end 0.776 -0.776)
			(stroke
				(width 0.15)
				(type solid)
			)
			(layer "B.SilkS")
		)
		(fp_line
			(start 0.776 0.778)
			(end 0.776 0.974)
			(stroke
				(width 0.15)
				(type solid)
			)
			(layer "B.SilkS")
		)
		(fp_circle
			(center -0.903 0.999)
			(end -0.952 0.95)
			(stroke
				(width 0.15)
				(type solid)
			)
			(fill yes)
			(layer "B.SilkS")
		)
		(fp_rect
			(start 1.19 1.12)
			(end -1.2 -1.1)
			(stroke
				(width 0.05)
				(type solid)
			)
			(fill no)
			(layer "B.CrtYd")
		)
		(fp_line
			(start -0.653 -0.847)
			(end -0.653 0.678)
			(stroke
				(width 0.15)
				(type solid)
			)
			(layer "B.Fab")
		)
		(fp_line
			(start -0.653 -0.847)
			(end 0.651 -0.847)
			(stroke
				(width 0.15)
				(type solid)
			)
			(layer "B.Fab")
		)
		(fp_line
			(start -0.653 0.678)
			(end -0.453 0.849)
			(stroke
				(width 0.15)
				(type solid)
			)
			(layer "B.Fab")
		)
		(fp_line
			(start 0.651 -0.847)
			(end 0.651 0.849)
			(stroke
				(width 0.15)
				(type solid)
			)
			(layer "B.Fab")
		)
		(fp_line
			(start 0.651 0.849)
			(end -0.453 0.849)
			(stroke
				(width 0.15)
				(type solid)
			)
			(layer "B.Fab")
		)
		(pad "1" smd roundrect
			(at -0.749 0.499 90)
			(size 0.3 0.6)
			(layers "B.Cu" "B.Mask" "B.Paste")
			(roundrect_rratio 0.25)
			(net 5 "+12V")
			(pinfunction "V_{IN}")
			(pintype "power_in")
		)
		(pad "2" smd roundrect
			(at -0.749 -0.001 90)
			(size 0.3 0.6)
			(layers "B.Cu" "B.Mask" "B.Paste")
			(roundrect_rratio 0.25)
			(net 21 "Net-(U3-SW)")
			(pinfunction "SW")
			(pintype "power_out")
		)
		(pad "3" smd roundrect
			(at -0.749 -0.497 90)
			(size 0.3 0.6)
			(layers "B.Cu" "B.Mask" "B.Paste")
			(roundrect_rratio 0.25)
			(net 2 "GND")
			(pinfunction "GND")
			(pintype "power_in")
		)
		(pad "4" smd roundrect
			(at 0.747 -0.497 90)
			(size 0.3 0.6)
			(layers "B.Cu" "B.Mask" "B.Paste")
			(roundrect_rratio 0.25)
			(net 22 "Net-(U3-BST)")
			(pinfunction "BST")
			(pintype "output")
		)
		(pad "5" smd roundrect
			(at 0.747 -0.001 90)
			(size 0.3 0.6)
			(layers "B.Cu" "B.Mask" "B.Paste")
			(roundrect_rratio 0.25)
			(net 47 "Net-(U3-EN)")
			(pinfunction "EN")
			(pintype "input")
		)
		(pad "6" smd roundrect
			(at 0.747 0.499 90)
			(size 0.3 0.6)
			(layers "B.Cu" "B.Mask" "B.Paste")
			(roundrect_rratio 0.25)
			(net 40 "Net-(U3-FB)")
			(pinfunction "FB")
			(pintype "input")
		)
	)
	(footprint "antmicro-footprints:C_1206_3216Metric"
		(layer "B.Cu")
		(at 95.8 97.85 90)
		(descr "Capacitor SMD 1206")
		(tags "capacitor SMD 1206")
		(property "Reference" "C20"
			(at 25.968 -9.438 0)
			(layer "B.SilkS")
			(effects
				(font
					(size 0.7 0.7)
					(thickness 0.15)
				)
				(justify left bottom mirror)
			)
		)
		(property "Value" "C_47u_25V_1206"
			(at 0 -2.101 90)
			(layer "B.Fab")
			(effects
				(font
					(size 0.7 0.7)
					(thickness 0.15)
				)
				(justify right bottom mirror)
			)
		)
		(property "Datasheet" "https://product.tdk.com/en/search/capacitor/ceramic/mlcc/info?part_no=C3216X5R1E476M160AC"
			(at 0 0 90)
			(layer "F.Fab")
			(hide yes)
			(effects
				(font
					(size 1.27 1.27)
					(thickness 0.15)
				)
			)
		)
		(property "Description" "SMD Multilayer Ceramic Capacitor, 47 µF, 25 V, 1206 [3216 Metric], ± 20%, X5R"
			(at 0 0 90)
			(layer "F.Fab")
			(hide yes)
			(effects
				(font
					(size 1.27 1.27)
					(thickness 0.15)
				)
			)
		)
		(property "MPN" "C3216X5R1E476M160AC"
			(at 0 0 90)
			(unlocked yes)
			(layer "B.Fab")
			(hide yes)
			(effects
				(font
					(size 1 1)
					(thickness 0.15)
				)
				(justify mirror)
			)
		)
		(property "Val" "47u"
			(at 0 0 90)
			(unlocked yes)
			(layer "B.Fab")
			(hide yes)
			(effects
				(font
					(size 1 1)
					(thickness 0.15)
				)
				(justify mirror)
			)
		)
		(property "Voltage" "25V"
			(at 0 0 90)
			(unlocked yes)
			(layer "B.Fab")
			(hide yes)
			(effects
				(font
					(size 1 1)
					(thickness 0.15)
				)
				(justify mirror)
			)
		)
		(property "Author" "Antmicro"
			(at 0 0 90)
			(unlocked yes)
			(layer "B.Fab")
			(hide yes)
			(effects
				(font
					(size 1 1)
					(thickness 0.15)
				)
				(justify mirror)
			)
		)
		(property "License" "Apache-2.0"
			(at 0 0 90)
			(unlocked yes)
			(layer "B.Fab")
			(hide yes)
			(effects
				(font
					(size 1 1)
					(thickness 0.15)
				)
				(justify mirror)
			)
		)
		(property "Manufacturer" "TDK"
			(at 0 0 90)
			(unlocked yes)
			(layer "B.Fab")
			(hide yes)
			(effects
				(font
					(size 1 1)
					(thickness 0.15)
				)
				(justify mirror)
			)
		)
		(property "Dielectric" "X5R"
			(at 0 0 90)
			(unlocked yes)
			(layer "B.Fab")
			(hide yes)
			(effects
				(font
					(size 1 1)
					(thickness 0.15)
				)
				(justify mirror)
			)
		)
		(property "Public" "False"
			(at 0 0 90)
			(unlocked yes)
			(layer "B.Fab")
			(hide yes)
			(effects
				(font
					(size 1 1)
					(thickness 0.15)
				)
				(justify mirror)
			)
		)
		(sheetname "/DC-DC Converters/")
		(sheetfile "dc-dc_converters.kicad_sch")
		(attr smd)
		(fp_line
			(start -0.8 -0.901)
			(end 0.8 -0.901)
			(stroke
				(width 0.15)
				(type solid)
			)
			(layer "B.SilkS")
		)
		(fp_line
			(start -0.8 0.899)
			(end 0.8 0.899)
			(stroke
				(width 0.15)
				(type solid)
			)
			(layer "B.SilkS")
		)
		(fp_rect
			(start -2.325 1.15)
			(end 2.325 -1.15)
			(stroke
				(width 0.05)
				(type default)
			)
			(fill no)
			(layer "B.CrtYd")
		)
		(fp_rect
			(start -1.6 0.799)
			(end 1.6 -0.801)
			(stroke
				(width 0.15)
				(type solid)
			)
			(fill no)
			(layer "B.Fab")
		)
		(pad "1" smd roundrect
			(at -1.5 -0.001 90)
			(size 1.15 1.8)
			(layers "B.Cu" "B.Mask" "B.Paste")
			(roundrect_rratio 0.25)
			(net 2 "GND")
			(pintype "passive")
		)
		(pad "2" smd roundrect
			(at 1.5 -0.001 90)
			(size 1.15 1.8)
			(layers "B.Cu" "B.Mask" "B.Paste")
			(roundrect_rratio 0.25)
			(net 5 "+12V")
			(pintype "passive")
		)
	)
	(footprint "antmicro-footprints:C_0603_1608Metric"
		(layer "B.Cu")
		(at 82.55 82.8 90)
		(descr "Capacitor SMD 0603")
		(tags "capacitor 0603")
		(property "Reference" "C26"
			(at 6.473 0.211 270)
			(layer "B.SilkS")
			(effects
				(font
					(size 0.7 0.7)
					(thickness 0.15)
				)
				(justify left bottom mirror)
			)
		)
		(property "Value" "C_10u_25V_0603"
			(at -1.42757 -1.770288 90)
			(layer "B.Fab")
			(effects
				(font
					(size 0.7 0.7)
					(thickness 0.15)
				)
				(justify right bottom mirror)
			)
		)
		(property "Datasheet" "https://product.tdk.com/en/search/capacitor/ceramic/mlcc/info?part_no=C1608X5R1E106M080AC"
			(at 0 0 90)
			(layer "F.Fab")
			(hide yes)
			(effects
				(font
					(size 1.27 1.27)
					(thickness 0.15)
				)
			)
		)
		(property "Description" "SMD Multilayer Ceramic Capacitor, 10 µF, 25 V, 0603 [1608 Metric], ± 20%, X5R, C"
			(at 0 0 90)
			(layer "F.Fab")
			(hide yes)
			(effects
				(font
					(size 1.27 1.27)
					(thickness 0.15)
				)
			)
		)
		(property "MPN" "C1608X5R1E106M080AC"
			(at 0 0 90)
			(unlocked yes)
			(layer "B.Fab")
			(hide yes)
			(effects
				(font
					(size 1 1)
					(thickness 0.15)
				)
				(justify mirror)
			)
		)
		(property "Manufacturer" "TDK"
			(at 0 0 90)
			(unlocked yes)
			(layer "B.Fab")
			(hide yes)
			(effects
				(font
					(size 1 1)
					(thickness 0.15)
				)
				(justify mirror)
			)
		)
		(property "License" "Apache-2.0"
			(at 0 0 90)
			(unlocked yes)
			(layer "B.Fab")
			(hide yes)
			(effects
				(font
					(size 1 1)
					(thickness 0.15)
				)
				(justify mirror)
			)
		)
		(property "Author" "Antmicro"
			(at 0 0 90)
			(unlocked yes)
			(layer "B.Fab")
			(hide yes)
			(effects
				(font
					(size 1 1)
					(thickness 0.15)
				)
				(justify mirror)
			)
		)
		(property "Val" "10u"
			(at 0 0 90)
			(unlocked yes)
			(layer "B.Fab")
			(hide yes)
			(effects
				(font
					(size 1 1)
					(thickness 0.15)
				)
				(justify mirror)
			)
		)
		(property "Voltage" "25V"
			(at 0 0 90)
			(unlocked yes)
			(layer "B.Fab")
			(hide yes)
			(effects
				(font
					(size 1 1)
					(thickness 0.15)
				)
				(justify mirror)
			)
		)
		(property "Dielectric" ""
			(at 0 0 90)
			(unlocked yes)
			(layer "B.Fab")
			(hide yes)
			(effects
				(font
					(size 1 1)
					(thickness 0.15)
				)
				(justify mirror)
			)
		)
		(sheetname "/DC-DC Converters/")
		(sheetfile "dc-dc_converters.kicad_sch")
		(attr smd)
		(fp_line
			(start 0.15 -0.4)
			(end -0.15 -0.4)
			(stroke
				(width 0.15)
				(type solid)
			)
			(layer "B.SilkS")
		)
		(fp_line
			(start 0.15 0.4)
			(end -0.15 0.4)
			(stroke
				(width 0.15)
				(type solid)
			)
			(layer "B.SilkS")
		)
		(fp_rect
			(start -1.25 0.65)
			(end 1.25 -0.65)
			(stroke
				(width 0.05)
				(type solid)
			)
			(fill no)
			(layer "B.CrtYd")
		)
		(fp_rect
			(start -0.8 0.4)
			(end 0.8 -0.4)
			(stroke
				(width 0.15)
				(type solid)
			)
			(fill no)
			(layer "B.Fab")
		)
		(pad "1" smd roundrect
			(at -0.7 0 90)
			(size 0.8 1)
			(layers "B.Cu" "B.Mask" "B.Paste")
			(roundrect_rratio 0.2)
			(net 2 "GND")
			(pintype "passive")
		)
		(pad "2" smd roundrect
			(at 0.7 0 90)
			(size 0.8 1)
			(layers "B.Cu" "B.Mask" "B.Paste")
			(roundrect_rratio 0.2)
			(net 1 "+3V3")
			(pintype "passive")
		)
	)
	(footprint "antmicro-footprints:R_0402_1005Metric"
		(layer "B.Cu")
		(at 87.4 80.5 -90)
		(descr "Resistor SMD 0402")
		(tags "resistor SMD 0402")
		(property "Reference" "R24"
			(at -3.157 -0.484 90)
			(layer "B.SilkS")
			(effects
				(font
					(size 0.7 0.7)
					(thickness 0.15)
				)
				(justify left bottom mirror)
			)
		)
		(property "Value" "R_15k_0402"
			(at -1.011843 -1.772047 90)
			(layer "B.Fab")
			(effects
				(font
					(size 0.7 0.7)
					(thickness 0.15)
				)
				(justify left bottom mirror)
			)
		)
		(property "Datasheet" "https://www.bourns.com/docs/product-datasheets/cr.pdf"
			(at 0 0 270)
			(layer "F.Fab")
			(hide yes)
			(effects
				(font
					(size 1.27 1.27)
					(thickness 0.15)
				)
			)
		)
		(property "Description" "SMD Chip Resistor, 15 kohm, ± 1%, 62.5 mW, 0402 [1005 Metric], Thick Film, General Purpose"
			(at 0 0 270)
			(layer "F.Fab")
			(hide yes)
			(effects
				(font
					(size 1.27 1.27)
					(thickness 0.15)
				)
			)
		)
		(property "MPN" "CR0402-FX-1502GLF"
			(at 0 0 270)
			(unlocked yes)
			(layer "B.Fab")
			(hide yes)
			(effects
				(font
					(size 1 1)
					(thickness 0.15)
				)
				(justify mirror)
			)
		)
		(property "Manufacturer" "Bourns"
			(at 0 0 270)
			(unlocked yes)
			(layer "B.Fab")
			(hide yes)
			(effects
				(font
					(size 1 1)
					(thickness 0.15)
				)
				(justify mirror)
			)
		)
		(property "License" "Apache-2.0"
			(at 0 0 270)
			(unlocked yes)
			(layer "B.Fab")
			(hide yes)
			(effects
				(font
					(size 1 1)
					(thickness 0.15)
				)
				(justify mirror)
			)
		)
		(property "Author" "Antmicro"
			(at 0 0 270)
			(unlocked yes)
			(layer "B.Fab")
			(hide yes)
			(effects
				(font
					(size 1 1)
					(thickness 0.15)
				)
				(justify mirror)
			)
		)
		(property "Val" "15k"
			(at 0 0 270)
			(unlocked yes)
			(layer "B.Fab")
			(hide yes)
			(effects
				(font
					(size 1 1)
					(thickness 0.15)
				)
				(justify mirror)
			)
		)
		(property "Tolerance" "1%"
			(at 0 0 270)
			(unlocked yes)
			(layer "B.Fab")
			(hide yes)
			(effects
				(font
					(size 1 1)
					(thickness 0.15)
				)
				(justify mirror)
			)
		)
		(sheetname "/DC-DC Converters/")
		(sheetfile "dc-dc_converters.kicad_sch")
		(attr smd)
		(fp_rect
			(start -0.925 0.47)
			(end 0.925 -0.47)
			(stroke
				(width 0.05)
				(type default)
			)
			(fill no)
			(layer "B.CrtYd")
		)
		(fp_rect
			(start -0.5 0.25)
			(end 0.5 -0.25)
			(stroke
				(width 0.15)
				(type solid)
			)
			(fill no)
			(layer "B.Fab")
		)
		(pad "1" smd roundrect
			(at -0.48 0 270)
			(size 0.59 0.64)
			(layers "B.Cu" "B.Mask" "B.Paste")
			(roundrect_rratio 0.25)
			(net 2 "GND")
			(pintype "passive")
		)
		(pad "2" smd roundrect
			(at 0.48 0 270)
			(size 0.59 0.64)
			(layers "B.Cu" "B.Mask" "B.Paste")
			(roundrect_rratio 0.25)
			(net 9 "Net-(U4-EN)")
			(pintype "passive")
		)
	)
	(footprint "antmicro-footprints:C_1206_3216Metric"
		(layer "B.Cu")
		(at 88.9 97.85 90)
		(descr "Capacitor SMD 1206")
		(tags "capacitor SMD 1206")
		(property "Reference" "C37"
			(at 22.158 -2.538 0)
			(layer "B.SilkS")
			(effects
				(font
					(size 0.7 0.7)
					(thickness 0.15)
				)
				(justify left bottom mirror)
			)
		)
		(property "Value" "C_47u_25V_1206"
			(at 0 -2.101 90)
			(layer "B.Fab")
			(effects
				(font
					(size 0.7 0.7)
					(thickness 0.15)
				)
				(justify right bottom mirror)
			)
		)
		(property "Datasheet" "https://product.tdk.com/en/search/capacitor/ceramic/mlcc/info?part_no=C3216X5R1E476M160AC"
			(at 0 0 90)
			(layer "F.Fab")
			(hide yes)
			(effects
				(font
					(size 1.27 1.27)
					(thickness 0.15)
				)
			)
		)
		(property "Description" "SMD Multilayer Ceramic Capacitor, 47 µF, 25 V, 1206 [3216 Metric], ± 20%, X5R"
			(at 0 0 90)
			(layer "F.Fab")
			(hide yes)
			(effects
				(font
					(size 1.27 1.27)
					(thickness 0.15)
				)
			)
		)
		(property "MPN" "C3216X5R1E476M160AC"
			(at 0 0 90)
			(unlocked yes)
			(layer "B.Fab")
			(hide yes)
			(effects
				(font
					(size 1 1)
					(thickness 0.15)
				)
				(justify mirror)
			)
		)
		(property "Val" "47u"
			(at 0 0 90)
			(unlocked yes)
			(layer "B.Fab")
			(hide yes)
			(effects
				(font
					(size 1 1)
					(thickness 0.15)
				)
				(justify mirror)
			)
		)
		(property "Voltage" "25V"
			(at 0 0 90)
			(unlocked yes)
			(layer "B.Fab")
			(hide yes)
			(effects
				(font
					(size 1 1)
					(thickness 0.15)
				)
				(justify mirror)
			)
		)
		(property "Author" "Antmicro"
			(at 0 0 90)
			(unlocked yes)
			(layer "B.Fab")
			(hide yes)
			(effects
				(font
					(size 1 1)
					(thickness 0.15)
				)
				(justify mirror)
			)
		)
		(property "License" "Apache-2.0"
			(at 0 0 90)
			(unlocked yes)
			(layer "B.Fab")
			(hide yes)
			(effects
				(font
					(size 1 1)
					(thickness 0.15)
				)
				(justify mirror)
			)
		)
		(property "Manufacturer" "TDK"
			(at 0 0 90)
			(unlocked yes)
			(layer "B.Fab")
			(hide yes)
			(effects
				(font
					(size 1 1)
					(thickness 0.15)
				)
				(justify mirror)
			)
		)
		(property "Dielectric" "X5R"
			(at 0 0 90)
			(unlocked yes)
			(layer "B.Fab")
			(hide yes)
			(effects
				(font
					(size 1 1)
					(thickness 0.15)
				)
				(justify mirror)
			)
		)
		(property "Public" "False"
			(at 0 0 90)
			(unlocked yes)
			(layer "B.Fab")
			(hide yes)
			(effects
				(font
					(size 1 1)
					(thickness 0.15)
				)
				(justify mirror)
			)
		)
		(sheetname "/DC-DC Converters/")
		(sheetfile "dc-dc_converters.kicad_sch")
		(attr smd)
		(fp_line
			(start -0.8 -0.901)
			(end 0.8 -0.901)
			(stroke
				(width 0.15)
				(type solid)
			)
			(layer "B.SilkS")
		)
		(fp_line
			(start -0.8 0.899)
			(end 0.8 0.899)
			(stroke
				(width 0.15)
				(type solid)
			)
			(layer "B.SilkS")
		)
		(fp_rect
			(start -2.325 1.15)
			(end 2.325 -1.15)
			(stroke
				(width 0.05)
				(type default)
			)
			(fill no)
			(layer "B.CrtYd")
		)
		(fp_rect
			(start -1.6 0.799)
			(end 1.6 -0.801)
			(stroke
				(width 0.15)
				(type solid)
			)
			(fill no)
			(layer "B.Fab")
		)
		(pad "1" smd roundrect
			(at -1.5 -0.001 90)
			(size 1.15 1.8)
			(layers "B.Cu" "B.Mask" "B.Paste")
			(roundrect_rratio 0.25)
			(net 2 "GND")
			(pintype "passive")
		)
		(pad "2" smd roundrect
			(at 1.5 -0.001 90)
			(size 1.15 1.8)
			(layers "B.Cu" "B.Mask" "B.Paste")
			(roundrect_rratio 0.25)
			(net 5 "+12V")
			(pintype "passive")
		)
	)
	(footprint "antmicro-footprints:L_1008_2520Metric"
		(layer "B.Cu")
		(at 83.85 80.1 180)
		(descr "Inductor SMD 1008 (2520 Metric)")
		(tags "inductor")
		(property "Reference" "L3"
			(at -1.748 1.487 0)
			(layer "B.SilkS")
			(effects
				(font
					(size 0.7 0.7)
					(thickness 0.15)
				)
				(justify left bottom mirror)
			)
		)
		(property "Value" "L_3u3_2.5A_1008"
			(at 0 -2.5 0)
			(layer "B.Fab")
			(effects
				(font
					(size 0.7 0.7)
					(thickness 0.15)
				)
				(justify left bottom mirror)
			)
		)
		(property "Datasheet" "https://product.tdk.com/system/files/dam/doc/product/inductor/inductor/smd/catalog/inductor_automotive_power_tfm252012alma_en.pdf"
			(at 0 0 180)
			(layer "F.Fab")
			(hide yes)
			(effects
				(font
					(size 1.27 1.27)
					(thickness 0.15)
				)
			)
		)
		(property "Description" "3.3 µH Shielded Thin Film Inductor 2 A 140mOhm Max 1008 (2520 Metric)"
			(at 0 0 180)
			(layer "F.Fab")
			(hide yes)
			(effects
				(font
					(size 1.27 1.27)
					(thickness 0.15)
				)
			)
		)
		(property "MPN" "TFM252012ALMA3R3MTAA"
			(at 0 0 180)
			(unlocked yes)
			(layer "B.Fab")
			(hide yes)
			(effects
				(font
					(size 1 1)
					(thickness 0.15)
				)
				(justify mirror)
			)
		)
		(property "ISat" "2.1 A"
			(at 0 0 180)
			(unlocked yes)
			(layer "B.Fab")
			(hide yes)
			(effects
				(font
					(size 1 1)
					(thickness 0.15)
				)
				(justify mirror)
			)
		)
		(property "IMax" "2.5 A"
			(at 0 0 180)
			(unlocked yes)
			(layer "B.Fab")
			(hide yes)
			(effects
				(font
					(size 1 1)
					(thickness 0.15)
				)
				(justify mirror)
			)
		)
		(property "Manufacturer" "TDK"
			(at 0 0 180)
			(unlocked yes)
			(layer "B.Fab")
			(hide yes)
			(effects
				(font
					(size 1 1)
					(thickness 0.15)
				)
				(justify mirror)
			)
		)
		(property "Val" "3u3/2.5A"
			(at 0 0 180)
			(unlocked yes)
			(layer "B.Fab")
			(hide yes)
			(effects
				(font
					(size 1 1)
					(thickness 0.15)
				)
				(justify mirror)
			)
		)
		(property "Size" "2.5x2.0"
			(at 0 0 180)
			(unlocked yes)
			(layer "B.Fab")
			(hide yes)
			(effects
				(font
					(size 1 1)
					(thickness 0.15)
				)
				(justify mirror)
			)
		)
		(property "Author" "Antmicro"
			(at 0 0 180)
			(unlocked yes)
			(layer "B.Fab")
			(hide yes)
			(effects
				(font
					(size 1 1)
					(thickness 0.15)
				)
				(justify mirror)
			)
		)
		(property "License" "Apache-2.0"
			(at 0 0 180)
			(unlocked yes)
			(layer "B.Fab")
			(hide yes)
			(effects
				(font
					(size 1 1)
					(thickness 0.15)
				)
				(justify mirror)
			)
		)
		(sheetname "/DC-DC Converters/")
		(sheetfile "dc-dc_converters.kicad_sch")
		(attr smd)
		(fp_line
			(start 0.261 1.111)
			(end -0.264 1.111)
			(stroke
				(width 0.15)
				(type solid)
			)
			(layer "B.SilkS")
		)
		(fp_line
			(start 0.261 -1.11)
			(end -0.264 -1.11)
			(stroke
				(width 0.15)
				(type solid)
			)
			(layer "B.SilkS")
		)
		(fp_rect
			(start -1.95 1.25)
			(end 1.95 -1.25)
			(stroke
				(width 0.05)
				(type solid)
			)
			(fill no)
			(layer "B.CrtYd")
		)
		(fp_line
			(start 1.249 0.999)
			(end -1.05 0.999)
			(stroke
				(width 0.15)
				(type solid)
			)
			(layer "B.Fab")
		)
		(fp_line
			(start 1.249 -0.997)
			(end 1.249 0.999)
			(stroke
				(width 0.15)
				(type solid)
			)
			(layer "B.Fab")
		)
		(fp_line
			(start -1.05 0.999)
			(end -1.25 0.8)
			(stroke
				(width 0.15)
				(type solid)
			)
			(layer "B.Fab")
		)
		(fp_line
			(start -1.25 0.8)
			(end -1.25 -0.997)
			(stroke
				(width 0.15)
				(type solid)
			)
			(layer "B.Fab")
		)
		(fp_line
			(start -1.25 -0.997)
			(end 1.249 -0.997)
			(stroke
				(width 0.15)
				(type solid)
			)
			(layer "B.Fab")
		)
		(pad "1" smd roundrect
			(at -1.075 0 180)
			(size 1.25 2.2)
			(layers "B.Cu" "B.Mask" "B.Paste")
			(roundrect_rratio 0.1)
			(net 23 "Net-(U4-SW)")
			(pintype "passive")
		)
		(pad "2" smd roundrect
			(at 1.075 0 180)
			(size 1.25 2.2)
			(layers "B.Cu" "B.Mask" "B.Paste")
			(roundrect_rratio 0.1)
			(net 1 "+3V3")
			(pintype "passive")
		)
	)
	(footprint "antmicro-footprints:R_0402_1005Metric"
		(layer "B.Cu")
		(at 87.401 86.7 -90)
		(descr "Resistor SMD 0402")
		(tags "resistor SMD 0402")
		(property "Reference" "R23"
			(at -1.083 -3.101 270)
			(layer "B.SilkS")
			(effects
				(font
					(size 0.7 0.7)
					(thickness 0.15)
				)
				(justify left bottom mirror)
			)
		)
		(property "Value" "R_15k_0402"
			(at -1.011843 -1.772047 90)
			(layer "B.Fab")
			(effects
				(font
					(size 0.7 0.7)
					(thickness 0.15)
				)
				(justify left bottom mirror)
			)
		)
		(property "Datasheet" "https://www.bourns.com/docs/product-datasheets/cr.pdf"
			(at 0 0 270)
			(layer "F.Fab")
			(hide yes)
			(effects
				(font
					(size 1.27 1.27)
					(thickness 0.15)
				)
			)
		)
		(property "Description" "SMD Chip Resistor, 15 kohm, ± 1%, 62.5 mW, 0402 [1005 Metric], Thick Film, General Purpose"
			(at 0 0 270)
			(layer "F.Fab")
			(hide yes)
			(effects
				(font
					(size 1.27 1.27)
					(thickness 0.15)
				)
			)
		)
		(property "MPN" "CR0402-FX-1502GLF"
			(at 0 0 270)
			(unlocked yes)
			(layer "B.Fab")
			(hide yes)
			(effects
				(font
					(size 1 1)
					(thickness 0.15)
				)
				(justify mirror)
			)
		)
		(property "Manufacturer" "Bourns"
			(at 0 0 270)
			(unlocked yes)
			(layer "B.Fab")
			(hide yes)
			(effects
				(font
					(size 1 1)
					(thickness 0.15)
				)
				(justify mirror)
			)
		)
		(property "License" "Apache-2.0"
			(at 0 0 270)
			(unlocked yes)
			(layer "B.Fab")
			(hide yes)
			(effects
				(font
					(size 1 1)
					(thickness 0.15)
				)
				(justify mirror)
			)
		)
		(property "Author" "Antmicro"
			(at 0 0 270)
			(unlocked yes)
			(layer "B.Fab")
			(hide yes)
			(effects
				(font
					(size 1 1)
					(thickness 0.15)
				)
				(justify mirror)
			)
		)
		(property "Val" "15k"
			(at 0 0 270)
			(unlocked yes)
			(layer "B.Fab")
			(hide yes)
			(effects
				(font
					(size 1 1)
					(thickness 0.15)
				)
				(justify mirror)
			)
		)
		(property "Tolerance" "1%"
			(at 0 0 270)
			(unlocked yes)
			(layer "B.Fab")
			(hide yes)
			(effects
				(font
					(size 1 1)
					(thickness 0.15)
				)
				(justify mirror)
			)
		)
		(sheetname "/DC-DC Converters/")
		(sheetfile "dc-dc_converters.kicad_sch")
		(attr smd)
		(fp_rect
			(start -0.925 0.47)
			(end 0.925 -0.47)
			(stroke
				(width 0.05)
				(type default)
			)
			(fill no)
			(layer "B.CrtYd")
		)
		(fp_rect
			(start -0.5 0.25)
			(end 0.5 -0.25)
			(stroke
				(width 0.15)
				(type solid)
			)
			(fill no)
			(layer "B.Fab")
		)
		(pad "1" smd roundrect
			(at -0.48 0 270)
			(size 0.59 0.64)
			(layers "B.Cu" "B.Mask" "B.Paste")
			(roundrect_rratio 0.25)
			(net 2 "GND")
			(pintype "passive")
		)
		(pad "2" smd roundrect
			(at 0.48 0 270)
			(size 0.59 0.64)
			(layers "B.Cu" "B.Mask" "B.Paste")
			(roundrect_rratio 0.25)
			(net 47 "Net-(U3-EN)")
			(pintype "passive")
		)
	)
	(footprint "antmicro-footprints:C_0402_1005Metric"
		(layer "B.Cu")
		(at 96.4 87.05 -90)
		(descr "Capacitor SMD 0402")
		(tags "capacitor SMD 0402")
		(property "Reference" "C41"
			(at -1.1 0.6 270)
			(layer "B.SilkS")
			(effects
				(font
					(size 0.7 0.7)
					(thickness 0.15)
				)
				(justify left bottom mirror)
			)
		)
		(property "Value" "C_1u_25V_0402"
			(at -1.022927 -2.155213 90)
			(layer "B.Fab")
			(effects
				(font
					(size 0.7 0.7)
					(thickness 0.15)
				)
				(justify left bottom mirror)
			)
		)
		(property "Datasheet" "https://www.murata.com/products/productdetail?partno=GRM155R61E105KE11%23"
			(at 0 0 270)
			(layer "F.Fab")
			(hide yes)
			(effects
				(font
					(size 1.27 1.27)
					(thickness 0.15)
				)
			)
		)
		(property "Description" "SMD Multilayer Ceramic Capacitor, 1 µF, 25 V, 0402 [1005 Metric], ± 10%, X5R, GRM Series"
			(at 0 0 270)
			(layer "F.Fab")
			(hide yes)
			(effects
				(font
					(size 1.27 1.27)
					(thickness 0.15)
				)
			)
		)
		(property "MPN" "GRM155R61E105KE11J"
			(at 0 0 270)
			(unlocked yes)
			(layer "B.Fab")
			(hide yes)
			(effects
				(font
					(size 1 1)
					(thickness 0.15)
				)
				(justify mirror)
			)
		)
		(property "Manufacturer" "Murata"
			(at 0 0 270)
			(unlocked yes)
			(layer "B.Fab")
			(hide yes)
			(effects
				(font
					(size 1 1)
					(thickness 0.15)
				)
				(justify mirror)
			)
		)
		(property "License" "Apache-2.0"
			(at 0 0 270)
			(unlocked yes)
			(layer "B.Fab")
			(hide yes)
			(effects
				(font
					(size 1 1)
					(thickness 0.15)
				)
				(justify mirror)
			)
		)
		(property "Author" "Antmicro"
			(at 0 0 270)
			(unlocked yes)
			(layer "B.Fab")
			(hide yes)
			(effects
				(font
					(size 1 1)
					(thickness 0.15)
				)
				(justify mirror)
			)
		)
		(property "Val" "1u"
			(at 0 0 270)
			(unlocked yes)
			(layer "B.Fab")
			(hide yes)
			(effects
				(font
					(size 1 1)
					(thickness 0.15)
				)
				(justify mirror)
			)
		)
		(property "Voltage" "25V"
			(at 0 0 270)
			(unlocked yes)
			(layer "B.Fab")
			(hide yes)
			(effects
				(font
					(size 1 1)
					(thickness 0.15)
				)
				(justify mirror)
			)
		)
		(property "Dielectric" "X5R"
			(at 0 0 270)
			(unlocked yes)
			(layer "B.Fab")
			(hide yes)
			(effects
				(font
					(size 1 1)
					(thickness 0.15)
				)
				(justify mirror)
			)
		)
		(sheetname "/DC-DC Converters/")
		(sheetfile "dc-dc_converters.kicad_sch")
		(attr smd)
		(fp_rect
			(start -0.925 0.47)
			(end 0.925 -0.47)
			(stroke
				(width 0.05)
				(type default)
			)
			(fill no)
			(layer "B.CrtYd")
		)
		(fp_line
			(start -0.494 0.25)
			(end -0.494 -0.248)
			(stroke
				(width 0.15)
				(type solid)
			)
			(layer "B.Fab")
		)
		(fp_line
			(start 0.504 0.25)
			(end -0.494 0.25)
			(stroke
				(width 0.15)
				(type solid)
			)
			(layer "B.Fab")
		)
		(fp_line
			(start -0.494 -0.248)
			(end 0.504 -0.248)
			(stroke
				(width 0.15)
				(type solid)
			)
			(layer "B.Fab")
		)
		(fp_line
			(start 0.504 -0.248)
			(end 0.504 0.25)
			(stroke
				(width 0.15)
				(type solid)
			)
			(layer "B.Fab")
		)
		(pad "1" smd roundrect
			(at -0.48 0 270)
			(size 0.59 0.64)
			(layers "B.Cu" "B.Mask" "B.Paste")
			(roundrect_rratio 0.25)
			(net 2 "GND")
			(pintype "passive")
		)
		(pad "2" smd roundrect
			(at 0.48 0 270)
			(size 0.59 0.64)
			(layers "B.Cu" "B.Mask" "B.Paste")
			(roundrect_rratio 0.25)
			(net 1 "+3V3")
			(pintype "passive")
		)
	)
	(gr_line
		(start 93.229817 71.070604)
		(end 93.229817 58.569417)
		(stroke
			(width 0.05)
			(type solid)
		)
		(layer "Edge.Cuts")
	)
	(gr_line
		(start 103.41223 100.625)
		(end 103.41223 71.070604)
		(stroke
			(width 0.05)
			(type solid)
		)
		(layer "Edge.Cuts")
	)
	(gr_line
		(start 93.229817 111.05)
		(end 93.229817 100.625)
		(stroke
			(width 0.05)
			(type default)
		)
		(layer "Edge.Cuts")
	)
	(gr_line
		(start 81.526 111.05)
		(end 93.229817 111.05)
		(stroke
			(width 0.05)
			(type default)
		)
		(layer "Edge.Cuts")
	)
	(gr_line
		(start 81.529836 58.569359)
		(end 81.529836 100.625018)
		(stroke
			(width 0.05)
			(type solid)
		)
		(layer "Edge.Cuts")
	)
	(gr_line
		(start 81.526 100.625018)
		(end 81.526 111.05)
		(stroke
			(width 0.05)
			(type default)
		)
		(layer "Edge.Cuts")
	)
	(gr_line
		(start 94.129811 71.070604)
		(end 93.229817 71.070604)
		(stroke
			(width 0.05)
			(type solid)
		)
		(layer "Edge.Cuts")
	)
	(gr_line
		(start 93.229817 58.569417)
		(end 81.529836 58.569359)
		(stroke
			(width 0.05)
			(type solid)
		)
		(layer "Edge.Cuts")
	)
	(gr_line
		(start 103.41223 71.070604)
		(end 94.129811 71.070604)
		(stroke
			(width 0.05)
			(type solid)
		)
		(layer "Edge.Cuts")
	)
	(gr_line
		(start 93.229817 100.625)
		(end 103.41223 100.625)
		(stroke
			(width 0.05)
			(type default)
		)
		(layer "Edge.Cuts")
	)
	(segment
		(start 101.926 72.35)
		(end 102.096 72.35)
		(width 0.2)
		(layer "F.Cu")
		(net 1)
	)
	(segment
		(start 82.35 69.27)
		(end 83.35 69.27)
		(width 0.2)
		(layer "F.Cu")
		(net 1)
	)
	(segment
		(start 82.35 69.27)
		(end 82.35 68.7)
		(width 0.2)
		(layer "F.Cu")
		(net 1)
	)
	(segment
		(start 91.086 80.38)
		(end 91.306 80.38)
		(width 0.25)
		(layer "F.Cu")
		(net 1)
	)
	(segment
		(start 88.9 69.8)
		(end 88.9 69.11)
		(width 0.4)
		(layer "F.Cu")
		(net 1)
	)
	(segment
		(start 102.096 72.35)
		(end 102.576 71.87)
		(width 0.2)
		(layer "F.Cu")
		(net 1)
	)
	(via
		(at 91.086 80.38)
		(size 0.45)
		(drill 0.2)
		(layers "F.Cu" "B.Cu")
		(net 1)
	)
	(via
		(at 98.4 87.3)
		(size 0.55)
		(drill 0.25)
		(layers "F.Cu" "B.Cu")
		(net 1)
	)
	(via
		(at 101.926 72.35)
		(size 0.55)
		(drill 0.25)
		(layers "F.Cu" "B.Cu")
		(net 1)
	)
	(via
		(at 83.017319 76.965929)
		(size 0.55)
		(drill 0.25)
		(layers "F.Cu" "B.Cu")
		(free yes)
		(net 1)
	)
	(via
		(at 82.5516 77.95)
		(size 0.55)
		(drill 0.25)
		(layers "F.Cu" "B.Cu")
		(free yes)
		(net 1)
	)
	(via
		(at 88.9 69.8)
		(size 0.55)
		(drill 0.25)
		(layers "F.Cu" "B.Cu")
		(net 1)
	)
	(via
		(at 82.35 68.7)
		(size 0.45)
		(drill 0.2)
		(layers "F.Cu" "B.Cu")
		(net 1)
	)
	(via
		(at 82.5516 77.3)
		(size 0.55)
		(drill 0.25)
		(layers "F.Cu" "B.Cu")
		(free yes)
		(net 1)
	)
	(via
		(at 99.002353 87.284574)
		(size 0.55)
		(drill 0.25)
		(layers "F.Cu" "B.Cu")
		(free yes)
		(net 1)
	)
	(segment
		(start 98.686927 87.6)
		(end 99.002353 87.284574)
		(width 0.4)
		(layer "B.Cu")
		(net 1)
	)
	(segment
		(start 98.181 87.6)
		(end 98.686927 87.6)
		(width 0.4)
		(layer "B.Cu")
		(net 1)
	)
	(segment
		(start 98.181 87.6)
		(end 98.181 87.519)
		(width 0.3)
		(layer "B.Cu")
		(net 1)
	)
	(segment
		(start 98.181 87.519)
		(end 98.4 87.3)
		(width 0.3)
		(layer "B.Cu")
		(net 1)
	)
	(segment
		(start 91.086 80.38)
		(end 89.12 80.38)
		(width 0.125)
		(layer "B.Cu")
		(net 1)
	)
	(segment
		(start 87.625 81.875)
		(end 87.625 82.42)
		(width 0.125)
		(layer "B.Cu")
		(net 1)
	)
	(segment
		(start 89.12 80.38)
		(end 87.625 81.875)
		(width 0.125)
		(layer "B.Cu")
		(net 1)
	)
	(segment
		(start 96.42 87.55)
		(end 96.4 87.53)
		(width 0.4)
		(layer "B.Cu")
		(net 1)
	)
	(segment
		(start 97.95 87.6)
		(end 97.9 87.55)
		(width 0.4)
		(layer "B.Cu")
		(net 1)
	)
	(segment
		(start 97.9 87.55)
		(end 96.42 87.55)
		(width 0.4)
		(layer "B.Cu")
		(net 1)
	)
	(segment
		(start 97.8 79.82)
		(end 98.659 79.82)
		(width 0.2)
		(layer "F.Cu")
		(net 2)
	)
	(segment
		(start 84.476 62.3)
		(end 85.102 61.674)
		(width 0.4)
		(layer "F.Cu")
		(net 2)
	)
	(segment
		(start 89.4 66.401)
		(end 89.4 65.55)
		(width 0.4)
		(layer "F.Cu")
		(net 2)
	)
	(segment
		(start 82.929199 73.648)
		(end 83.663 73.648)
		(width 0.2)
		(layer "F.Cu")
		(net 2)
	)
	(segment
		(start 87.538 73.15)
		(end 88.2 73.15)
		(width 0.125)
		(layer "F.Cu")
		(net 2)
	)
	(segment
		(start 89.88 70.98)
		(end 89.9 71)
		(width 0.125)
		(layer "F.Cu")
		(net 2)
	)
	(segment
		(start 99.497 85.6)
		(end 99.52 85.577)
		(width 0.2)
		(layer "F.Cu")
		(net 2)
	)
	(segment
		(start 98.659 79.82)
		(end 98.679 79.8)
		(width 0.2)
		(layer "F.Cu")
		(net 2)
	)
	(segment
		(start 95.85 87.223)
		(end 95.85 85.15)
		(width 0.25)
		(layer "F.Cu")
		(net 2)
	)
	(segment
		(start 84.476 62.75)
		(end 84.476 62.3)
		(width 0.4)
		(layer "F.Cu")
		(net 2)
	)
	(segment
		(start 96.18 88.52)
		(end 96.18 88.4)
		(width 0.4)
		(layer "F.Cu")
		(net 2)
	)
	(segment
		(start 98.8 85.6)
		(end 99.497 85.6)
		(width 0.2)
		(layer "F.Cu")
		(net 2)
	)
	(segment
		(start 89.48 65.63)
		(end 89.4 65.55)
		(width 0.5)
		(layer "F.Cu")
		(net 2)
	)
	(segment
		(start 97 75.25)
		(end 97 75.8)
		(width 0.3)
		(layer "F.Cu")
		(net 2)
	)
	(segment
		(start 89.48 67.2)
		(end 89.48 65.63)
		(width 0.5)
		(layer "F.Cu")
		(net 2)
	)
	(segment
		(start 89.88 73.7)
		(end 89.88 72.7)
		(width 0.2)
		(layer "F.Cu")
		(net 2)
	)
	(segment
		(start 89.151 66.65)
		(end 89.4 66.401)
		(width 0.4)
		(layer "F.Cu")
		(net 2)
	)
	(segment
		(start 89.48 67.2)
		(end 89.48 66.979)
		(width 0.3)
		(layer "F.Cu")
		(net 2)
	)
	(segment
		(start 86.9 68.987)
		(end 86.9 68.215)
		(width 0.2)
		(layer "F.Cu")
		(net 2)
	)
	(segment
		(start 85.102 61.674)
		(end 90.701 61.674)
		(width 0.5)
		(layer "F.Cu")
		(net 2)
	)
	(segment
		(start 96.266 84.734)
		(end 96.266 84.709)
		(width 0.25)
		(layer "F.Cu")
		(net 2)
	)
	(segment
		(start 82.881199 73.6)
		(end 82.929199 73.648)
		(width 0.2)
		(layer "F.Cu")
		(net 2)
	)
	(segment
		(start 90.701 61.674)
		(end 90.701 61.367)
		(width 1)
		(layer "F.Cu")
		(net 2)
	)
	(segment
		(start 97.1 89.48)
		(end 96.43 89.48)
		(width 0.3)
		(layer "F.Cu")
		(net 2)
	)
	(segment
		(start 89.88 70.9316)
		(end 89.88 70.98)
		(width 0.125)
		(layer "F.Cu")
		(net 2)
	)
	(segment
		(start 89.5 65.65)
		(end 89.4 65.55)
		(width 0.125)
		(layer "F.Cu")
		(net 2)
	)
	(segment
		(start 97.625 84.947)
		(end 96.547 84.947)
		(width 0.2)
		(layer "F.Cu")
		(net 2)
	)
	(segment
		(start 100.877 83.577)
		(end 100.48 83.577)
		(width 0.125)
		(layer "F.Cu")
		(net 2)
	)
	(segment
		(start 96.43 89.48)
		(end 95.887404 88.937404)
		(width 0.3)
		(layer "F.Cu")
		(net 2)
	)
	(segment
		(start 89.88 72.7)
		(end 89.88 71.7)
		(width 0.2)
		(layer "F.Cu")
		(net 2)
	)
	(segment
		(start 95.779041 88.920959)
		(end 96.18 88.52)
		(width 0.4)
		(layer "F.Cu")
		(net 2)
	)
	(segment
		(start 89.9 71.68)
		(end 89.88 71.7)
		(width 0.2)
		(layer "F.Cu")
		(net 2)
	)
	(segment
		(start 94.448823 75.686319)
		(end 94.2848 75.522296)
		(width 0.125)
		(layer "F.Cu")
		(net 2)
	)
	(segment
		(start 100.9 83.6)
		(end 100.877 83.577)
		(width 0.125)
		(layer "F.Cu")
		(net 2)
	)
	(segment
		(start 85.352 73.648)
		(end 85.6 73.4)
		(width 0.2)
		(layer "F.Cu")
		(net 2)
	)
	(segment
		(start 85.102 61.674)
		(end 85.102 61.313)
		(width 1)
		(layer "F.Cu")
		(net 2)
	)
	(segment
		(start 96.266 84.709)
		(end 96.291 84.709)
		(width 0.25)
		(layer "F.Cu")
		(net 2)
	)
	(segment
		(start 100.9 81.6)
		(end 100.877 81.577)
		(width 0.125)
		(layer "F.Cu")
		(net 2)
	)
	(segment
		(start 83.82 74.806)
		(end 83.663 74.649)
		(width 0.125)
		(layer "F.Cu")
		(net 2)
	)
	(segment
		(start 89.9 71.7)
		(end 89.88 71.72)
		(width 0.125)
		(layer "F.Cu")
		(net 2)
	)
	(segment
		(start 85.102 61.313)
		(end 83.608 59.819)
		(width 1)
		(layer "F.Cu")
		(net 2)
	)
	(segment
		(start 84.351 75.337)
		(end 84.198 75.184)
		(width 0.125)
		(layer "F.Cu")
		(net 2)
	)
	(segment
		(start 95.85 85.15)
		(end 96.266 84.734)
		(width 0.25)
		(layer "F.Cu")
		(net 2)
	)
	(segment
		(start 83.82 75.184)
		(end 83.82 74.806)
		(width 0.125)
		(layer "F.Cu")
		(net 2)
	)
	(segment
		(start 100.9 82.55)
		(end 100.873 82.577)
		(width 0.125)
		(layer "F.Cu")
		(net 2)
	)
	(segment
		(start 100.9 79.6)
		(end 100.877 79.577)
		(width 0.125)
		(layer "F.Cu")
		(net 2)
	)
	(segment
		(start 83.663 73.648)
		(end 85.352 73.648)
		(width 0.2)
		(layer "F.Cu")
		(net 2)
	)
	(segment
		(start 89.88 71.68)
		(end 89.9 71.7)
		(width 0.125)
		(layer "F.Cu")
		(net 2)
	)
	(segment
		(start 89.88 71.72)
		(end 89.88 73.7)
		(width 0.125)
		(layer "F.Cu")
		(net 2)
	)
	(segment
		(start 90.701 61.367)
		(end 92.249 59.819)
		(width 1)
		(layer "F.Cu")
		(net 2)
	)
	(segment
		(start 89.9 71)
		(end 89.9 71.68)
		(width 0.2)
		(layer "F.Cu")
		(net 2)
	)
	(segment
		(start 96.291 84.709)
		(end 96.3 84.7)
		(width 0.25)
		(layer "F.Cu")
		(net 2)
	)
	(segment
		(start 96.547 84.947)
		(end 96.3 84.7)
		(width 0.2)
		(layer "F.Cu")
		(net 2)
	)
	(segment
		(start 91.376 62.75)
		(end 91.376 62.349)
		(width 0.4)
		(layer "F.Cu")
		(net 2)
	)
	(segment
		(start 84.35 68.75)
		(end 84.35 69.27)
		(width 0.4)
		(layer "F.Cu")
		(net 2)
	)
	(segment
		(start 90.8628 81.32)
		(end 90.725 81.4578)
		(width 0.4)
		(layer "F.Cu")
		(net 2)
	)
	(segment
		(start 102.4 75.25)
		(end 101.05 75.25)
		(width 0.3)
		(layer "F.Cu")
		(net 2)
	)
	(segment
		(start 99.77 87.6)
		(end 99.770988 87.6)
		(width 0.4)
		(layer "F.Cu")
		(net 2)
	)
	(segment
		(start 95.779041 88.937404)
		(end 95.779041 88.920959)
		(width 0.4)
		(layer "F.Cu")
		(net 2)
	)
	(segment
		(start 84.198 75.184)
		(end 83.816 75.184)
		(width 0.125)
		(layer "F.Cu")
		(net 2)
	)
	(segment
		(start 100.873 82.577)
		(end 100.48 82.577)
		(width 0.125)
		(layer "F.Cu")
		(net 2)
	)
	(segment
		(start 89.9 71)
		(end 89.88 71.02)
		(width 0.125)
		(layer "F.Cu")
		(net 2)
	)
	(segment
		(start 89.48 66.979)
		(end 89.151 66.65)
		(width 0.3)
		(layer "F.Cu")
		(net 2)
	)
	(segment
		(start 100.877 79.577)
		(end 100.48 79.577)
		(width 0.125)
		(layer "F.Cu")
		(net 2)
	)
	(segment
		(start 101.05 75.25)
		(end 101.05 75.8)
		(width 0.3)
		(layer "F.Cu")
		(net 2)
	)
	(segment
		(start 86.9 68.215)
		(end 86.9 67.4)
		(width 0.2)
		(layer "F.Cu")
		(net 2)
	)
	(segment
		(start 91.5 81.32)
		(end 90.8628 81.32)
		(width 0.4)
		(layer "F.Cu")
		(net 2)
	)
	(segment
		(start 89.8652 70.9168)
		(end 89.88 70.9316)
		(width 0.125)
		(layer "F.Cu")
		(net 2)
	)
	(segment
		(start 95.887404 88.937404)
		(end 95.779041 88.937404)
		(width 0.3)
		(layer "F.Cu")
		(net 2)
	)
	(segment
		(start 100.877 81.577)
		(end 100.48 81.577)
		(width 0.125)
		(layer "F.Cu")
		(net 2)
	)
	(segment
		(start 91.376 62.349)
		(end 90.701 61.674)
		(width 0.4)
		(layer "F.Cu")
		(net 2)
	)
	(segment
		(start 99.770988 87.6)
		(end 100.044333 87.326655)
		(width 0.4)
		(layer "F.Cu")
		(net 2)
	)
	(via
		(at 91.076 99.85)
		(size 0.55)
		(drill 0.25)
		(layers "F.Cu" "B.Cu")
		(net 2)
	)
	(via
		(at 96.266 84.074)
		(size 0.45)
		(drill 0.2)
		(layers "F.Cu" "B.Cu")
		(net 2)
	)
	(via
		(at 97.001 99.85)
		(size 0.55)
		(drill 0.25)
		(layers "F.Cu" "B.Cu")
		(net 2)
	)
	(via
		(at 102.024946 90.931054)
		(size 0.55)
		(drill 0.25)
		(layers "F.Cu" "B.Cu")
		(net 2)
	)
	(via
		(at 91.376 62.15)
		(size 0.45)
		(drill 0.2)
		(layers "F.Cu" "B.Cu")
		(free yes)
		(net 2)
	)
	(via
		(at 91.75 67.35)
		(size 0.55)
		(drill 0.25)
		(layers "F.Cu" "B.Cu")
		(net 2)
	)
	(via
		(at 84.476 62.15)
		(size 0.45)
		(drill 0.2)
		(layers "F.Cu" "B.Cu")
		(free yes)
		(net 2)
	)
	(via
		(at 100.9 79.6)
		(size 0.45)
		(drill 0.2)
		(layers "F.Cu" "B.Cu")
		(net 2)
	)
	(via
		(at 96.266 84.709)
		(size 0.45)
		(drill 0.2)
		(layers "F.Cu" "B.Cu")
		(net 2)
	)
	(via
		(at 92.576 62.75)
		(size 0.45)
		(drill 0.2)
		(layers "F.Cu" "B.Cu")
		(free yes)
		(net 2)
	)
	(via
		(at 84.076 95.35)
		(size 0.55)
		(drill 0.25)
		(layers "F.Cu" "B.Cu")
		(free yes)
		(net 2)
	)
	(via
		(at 91.876 109.85)
		(size 0.55)
		(drill 0.25)
		(layers "F.Cu" "B.Cu")
		(free yes)
		(net 2)
	)
	(via
		(at 91.75 66.25)
		(size 0.55)
		(drill 0.25)
		(layers "F.Cu" "B.Cu")
		(net 2)
	)
	(via
		(at 83.876 62.15)
		(size 0.45)
		(drill 0.2)
		(layers "F.Cu" "B.Cu")
		(free yes)
		(net 2)
	)
	(via
		(at 89.9 71.7)
		(size 0.55)
		(drill 0.25)
		(layers "F.Cu" "B.Cu")
		(net 2)
	)
	(via
		(at 90.725 81.4578)
		(size 0.6)
		(drill 0.3)
		(layers "F.Cu" "B.Cu")
		(net 2)
	)
	(via
		(at 82.576 101.6)
		(size 0.55)
		(drill 0.25)
		(layers "F.Cu" "B.Cu")
		(free yes)
		(net 2)
	)
	(via
		(at 89.3 88.65)
		(size 0.55)
		(drill 0.25)
		(layers "F.Cu" "B.Cu")
		(free yes)
		(net 2)
	)
	(via
		(at 96.266 85.344)
		(size 0.45)
		(drill 0.2)
		(layers "F.Cu" "B.Cu")
		(net 2)
	)
	(via
		(at 102.076 86.85)
		(size 0.55)
		(drill 0.25)
		(layers "F.Cu" "B.Cu")
		(net 2)
	)
	(via
		(at 90 87.15)
		(size 0.55)
		(drill 0.25)
		(layers "F.Cu" "B.Cu")
		(free yes)
		(net 2)
	)
	(via
		(at 88.2 73.15)
		(size 0.45)
		(drill 0.2)
		(layers "F.Cu" "B.Cu")
		(net 2)
	)
	(via
		(at 98.451 99.85)
		(size 0.55)
		(drill 0.25)
		(layers "F.Cu" "B.Cu")
		(free yes)
		(net 2)
	)
	(via
		(at 88.276 98.4)
		(size 0.55)
		(drill 0.25)
		(layers "F.Cu" "B.Cu")
		(free yes)
		(net 2)
	)
	(via
		(at 100.9 81.6)
		(size 0.45)
		(drill 0.2)
		(layers "F.Cu" "B.Cu")
		(net 2)
	)
	(via
		(at 102.076 85.85)
		(size 0.55)
		(drill 0.25)
		(layers "F.Cu" "B.Cu")
		(net 2)
	)
	(via
		(at 90.805 86.741)
		(size 0.55)
		(drill 0.25)
		(layers "F.Cu" "B.Cu")
		(free yes)
		(net 2)
	)
	(via
		(at 98.8 85.6)
		(size 0.45)
		(drill 0.2)
		(layers "F.Cu" "B.Cu")
		(net 2)
	)
	(via
		(at 83.276 62.75)
		(size 0.45)
		(drill 0.2)
		(layers "F.Cu" "B.Cu")
		(free yes)
		(net 2)
	)
	(via
		(at 101.151 99.85)
		(size 0.55)
		(drill 0.25)
		(layers "F.Cu" "B.Cu")
		(free yes)
		(net 2)
	)
	(via
		(at 84.35 68.75)
		(size 0.55)
		(drill 0.25)
		(layers "F.Cu" "B.Cu")
		(net 2)
	)
	(via
		(at 83.225 82.8)
		(size 0.55)
		(drill 0.25)
		(layers "F.Cu" "B.Cu")
		(net 2)
	)
	(via
		(at 86.9 66.6)
		(size 0.45)
		(drill 0.2)
		(layers "F.Cu" "B.Cu")
		(net 2)
	)
	(via
		(at 91.976 62.15)
		(size 0.45)
		(drill 0.2)
		(layers "F.Cu" "B.Cu")
		(free yes)
		(net 2)
	)
	(via
		(at 97 75.8)
		(size 0.55)
		(drill 0.25)
		(layers "F.Cu" "B.Cu")
		(net 2)
	)
	(via
		(at 89.9 71)
		(size 0.55)
		(drill 0.25)
		(layers "F.Cu" "B.Cu")
		(net 2)
	)
	(via
		(at 83.9 66.5)
		(size 0.45)
		(drill 0.2)
		(layers "F.Cu" "B.Cu")
		(net 2)
	)
	(via
		(at 85.5 66.9)
		(size 0.45)
		(drill 0.2)
		(layers "F.Cu" "B.Cu")
		(net 2)
	)
	(via
		(at 91.948 87.122)
		(size 0.55)
		(drill 0.25)
		(layers "F.Cu" "B.Cu")
		(free yes)
		(net 2)
	)
	(via
		(at 82.4 66.9)
		(size 0.55)
		(drill 0.25)
		(layers "F.Cu" "B.Cu")
		(net 2)
	)
	(via
		(at 93.98 84.709)
		(size 0.45)
		(drill 0.2)
		(layers "F.Cu" "B.Cu")
		(net 2)
	)
	(via
		(at 86.9 67.4)
		(size 0.45)
		(drill 0.2)
		(layers "F.Cu" "B.Cu")
		(net 2)
	)
	(via
		(at 102.053554 89.046446)
		(size 0.55)
		(drill 0.25)
		(layers "F.Cu" "B.Cu")
		(net 2)
	)
	(via
		(at 82.4 66.25)
		(size 0.55)
		(drill 0.25)
		(layers "F.Cu" "B.Cu")
		(net 2)
	)
	(via
		(at 91.376 62.75)
		(size 0.45)
		(drill 0.2)
		(layers "F.Cu" "B.Cu")
		(free yes)
		(net 2)
	)
	(via
		(at 94.001 99.8)
		(size 0.55)
		(drill 0.25)
		(layers "F.Cu" "B.Cu")
		(free yes)
		(net 2)
	)
	(via
		(at 93.98 85.979)
		(size 0.45)
		(drill 0.2)
		(layers "F.Cu" "B.Cu")
		(net 2)
	)
	(via
		(at 82.55 82.9)
		(size 0.55)
		(drill 0.25)
		(layers "F.Cu" "B.Cu")
		(net 2)
	)
	(via
		(at 93.979999 85.344)
		(size 0.45)
		(drill 0.2)
		(layers "F.Cu" "B.Cu")
		(net 2)
	)
	(via
		(at 102.076 87.85)
		(size 0.55)
		(drill 0.25)
		(layers "F.Cu" "B.Cu")
		(net 2)
	)
	(via
		(at 91.75 86.5)
		(size 0.55)
		(drill 0.25)
		(layers "F.Cu" "B.Cu")
		(free yes)
		(net 2)
	)
	(via
		(at 82.576 103.1)
		(size 0.55)
		(drill 0.25)
		(layers "F.Cu" "B.Cu")
		(free yes)
		(net 2)
	)
	(via
		(at 82.601 95.35)
		(size 0.55)
		(drill 0.25)
		(layers "F.Cu" "B.Cu")
		(free yes)
		(net 2)
	)
	(via
		(at 96.266 85.979)
		(size 0.45)
		(drill 0.2)
		(layers "F.Cu" "B.Cu")
		(net 2)
	)
	(via
		(at 90.925 85)
		(size 0.55)
		(drill 0.25)
		(layers "F.Cu" "B.Cu")
		(free yes)
		(net 2)
	)
	(via
		(at 97.076 71.75)
		(size 0.45)
		(drill 0.2)
		(layers "F.Cu" "B.Cu")
		(free yes)
		(net 2)
	)
	(via
		(at 93.218 85.344)
		(size 0.45)
		(drill 0.2)
		(layers "F.Cu" "B.Cu")
		(net 2)
	)
	(via
		(at 95.001 99.85)
		(size 0.55)
		(drill 0.25)
		(layers "F.Cu" "B.Cu")
		(free yes)
		(net 2)
	)
	(via
		(at 82.881199 73.6)
		(size 0.45)
		(drill 0.2)
		(layers "F.Cu" "B.Cu")
		(net 2)
	)
	(via
		(at 99.351 99.85)
		(size 0.55)
		(drill 0.25)
		(layers "F.Cu" "B.Cu")
		(free yes)
		(net 2)
	)
	(via
		(at 98.679 79.8)
		(size 0.45)
		(drill 0.2)
		(layers "F.Cu" "B.Cu")
		(net 2)
	)
	(via
		(at 91.276 109.85)
		(size 0.55)
		(drill 0.25)
		(layers "F.Cu" "B.Cu")
		(free yes)
		(net 2)
	)
	(via
		(at 85.5 67.5)
		(size 0.45)
		(drill 0.2)
		(layers "F.Cu" "B.Cu")
		(net 2)
	)
	(via
		(at 100.9 82.55)
		(size 0.45)
		(drill 0.2)
		(layers "F.Cu" "B.Cu")
		(net 2)
	)
	(via
		(at 86.002761 79.149333)
		(size 0.55)
		(drill 0.25)
		(layers "F.Cu" "B.Cu")
		(net 2)
	)
	(via
		(at 100.044333 87.326655)
		(size 0.55)
		(drill 0.25)
		(layers "F.Cu" "B.Cu")
		(net 2)
	)
	(via
		(at 93.176 99.85)
		(size 0.55)
		(drill 0.25)
		(layers "F.Cu" "B.Cu")
		(net 2)
	)
	(via
		(at 89.151 66.65)
		(size 0.55)
		(drill 0.25)
		(layers "F.Cu" "B.Cu")
		(net 2)
	)
	(via
		(at 94.742 85.344)
		(size 0.45)
		(drill 0.2)
		(layers "F.Cu" "B.Cu")
		(net 2)
	)
	(via
		(at 88.251 85.4)
		(size 0.55)
		(drill 0.25)
		(layers "F.Cu" "B.Cu")
		(free yes)
		(net 2)
	)
	(via
		(at 90 86.5)
		(size 0.55)
		(drill 0.25)
		(layers "F.Cu" "B.Cu")
		(free yes)
		(net 2)
	)
	(via
		(at 84.476 62.75)
		(size 0.45)
		(drill 0.2)
		(layers "F.Cu" "B.Cu")
		(free yes)
		(net 2)
	)
	(via
		(at 92.476 109.85)
		(size 0.55)
		(drill 0.25)
		(layers "F.Cu" "B.Cu")
		(free yes)
		(net 2)
	)
	(via
		(at 87.3 85)
		(size 0.55)
		(drill 0.25)
		(layers "F.Cu" "B.Cu")
		(free yes)
		(net 2)
	)
	(via
		(at 102.051 99.85)
		(size 0.55)
		(drill 0.25)
		(layers "F.Cu" "B.Cu")
		(free yes)
		(net 2)
	)
	(via
		(at 97.076 72.75)
		(size 0.45)
		(drill 0.2)
		(layers "F.Cu" "B.Cu")
		(free yes)
		(net 2)
	)
	(via
		(at 82.576 102.35)
		(size 0.55)
		(drill 0.25)
		(layers "F.Cu" "B.Cu")
		(free yes)
		(net 2)
	)
	(via
		(at 90.876 98.95)
		(size 0.55)
		(drill 0.25)
		(layers "F.Cu" "B.Cu")
		(net 2)
	)
	(via
		(at 82.4 67.55)
		(size 0.55)
		(drill 0.25)
		(layers "F.Cu" "B.Cu")
		(net 2)
	)
	(via
		(at 83.9 67.3)
		(size 0.45)
		(drill 0.2)
		(layers "F.Cu" "B.Cu")
		(net 2)
	)
	(via
		(at 89.126 85.4)
		(size 0.55)
		(drill 0.25)
		(layers "F.Cu" "B.Cu")
		(free yes)
		(net 2)
	)
	(via
		(at 83.9 82.675)
		(size 0.55)
		(drill 0.25)
		(layers "F.Cu" "B.Cu")
		(net 2)
	)
	(via
		(at 89.076 99.85)
		(size 0.55)
		(drill 0.25)
		(layers "F.Cu" "B.Cu")
		(net 2)
	)
	(via
		(at 101.05 75.8)
		(size 0.55)
		(drill 0.25)
		(layers "F.Cu" "B.Cu")
		(net 2)
	)
	(via
		(at 102.73723 99.546657)
		(size 0.55)
		(drill 0.25)
		(layers "F.Cu" "B.Cu")
		(free yes)
		(net 2)
	)
	(via
		(at 92.554817 65.6)
		(size 0.55)
		(drill 0.25)
		(layers "F.Cu" "B.Cu")
		(free yes)
		(net 2)
	)
	(via
		(at 96.001 99.85)
		(size 0.55)
		(drill 0.25)
		(layers "F.Cu" "B.Cu")
		(free yes)
		(net 2)
	)
	(via
		(at 92.576 62.15)
		(size 0.45)
		(drill 0.2)
		(layers "F.Cu" "B.Cu")
		(free yes)
		(net 2)
	)
	(via
		(at 100.9 83.6)
		(size 0.45)
		(drill 0.2)
		(layers "F.Cu" "B.Cu")
		(net 2)
	)
	(via
		(at 90.076 99.85)
		(size 0.55)
		(drill 0.25)
		(layers "F.Cu" "B.Cu")
		(net 2)
	)
	(via
		(at 93.218 85.979)
		(size 0.45)
		(drill 0.2)
		(layers "F.Cu" "B.Cu")
		(net 2)
	)
	(via
		(at 83.326 95.35)
		(size 0.55)
		(drill 0.25)
		(layers "F.Cu" "B.Cu")
		(free yes)
		(net 2)
	)
	(via
		(at 94.742 84.709)
		(size 0.45)
		(drill 0.2)
		(layers "F.Cu" "B.Cu")
		(net 2)
	)
	(via
		(at 100.251 99.85)
		(size 0.55)
		(drill 0.25)
		(layers "F.Cu" "B.Cu")
		(free yes)
		(net 2)
	)
	(via
		(at 92.526 67.975)
		(size 0.45)
		(drill 0.2)
		(layers "F.Cu" "B.Cu")
		(net 2)
	)
	(via
		(at 83.876 62.75)
		(size 0.45)
		(drill 0.2)
		(layers "F.Cu" "B.Cu")
		(free yes)
		(net 2)
	)
	(via
		(at 89.076 98.4)
		(size 0.55)
		(drill 0.25)
		(layers "F.Cu" "B.Cu")
		(free yes)
		(net 2)
	)
	(via
		(at 85.5 66.3)
		(size 0.45)
		(drill 0.2)
		(layers "F.Cu" "B.Cu")
		(net 2)
	)
	(via
		(at 83.276 62.15)
		(size 0.45)
		(drill 0.2)
		(layers "F.Cu" "B.Cu")
		(free yes)
		(net 2)
	)
	(via
		(at 93.218 84.709)
		(size 0.45)
		(drill 0.2)
		(layers "F.Cu" "B.Cu")
		(net 2)
	)
	(via
		(at 83.82 75.184)
		(size 0.45)
		(drill 0.2)
		(layers "F.Cu" "B.Cu")
		(net 2)
	)
	(via
		(at 91.976 62.75)
		(size 0.45)
		(drill 0.2)
		(layers "F.Cu" "B.Cu")
		(free yes)
		(net 2)
	)
	(via
		(at 97.076 72.25)
		(size 0.45)
		(drill 0.2)
		(layers "F.Cu" "B.Cu")
		(free yes)
		(net 2)
	)
	(via
		(at 96.266 83.439)
		(size 0.45)
		(drill 0.2)
		(layers "F.Cu" "B.Cu")
		(net 2)
	)
	(via
		(at 95.779041 88.937404)
		(size 0.55)
		(drill 0.25)
		(layers "F.Cu" "B.Cu")
		(free yes)
		(net 2)
	)
	(via
		(at 82.576 100.85)
		(size 0.55)
		(drill 0.25)
		(layers "F.Cu" "B.Cu")
		(free yes)
		(net 2)
	)
	(via
		(at 92 98.4)
		(size 0.55)
		(drill 0.25)
		(layers "F.Cu" "B.Cu")
		(free yes)
		(net 2)
	)
	(segment
		(start 102.056 86.87)
		(end 102.056 87.83)
		(width 1.5)
		(layer "B.Cu")
		(net 2)
	)
	(segment
		(start 86.426 90.75)
		(end 88.276 90.75)
		(width 0.5)
		(layer "B.Cu")
		(net 2)
	)
	(segment
		(start 96.266 85.344)
		(end 96.266 84.709)
		(width 0.4)
		(layer "B.Cu")
		(net 2)
	)
	(segment
		(start 85.925 66.25)
		(end 85.925 67.552)
		(width 0.3)
		(layer "B.Cu")
		(net 2)
	)
	(segment
		(start 89.3 88.65)
		(end 89.27 88.62)
		(width 0.4)
		(layer "B.Cu")
		(net 2)
	)
	(segment
		(start 102.056 89.57)
		(end 101.976 89.65)
		(width 1.5)
		(layer "B.Cu")
		(net 2)
	)
	(segment
		(start 85.925 66.25)
		(end 86.55 66.25)
		(width 0.2)
		(layer "B.Cu")
		(net 2)
	)
	(segment
		(start 91.85 67.45)
		(end 91.75 67.35)
		(width 0.2)
		(layer "B.Cu")
		(net 2)
	)
	(segment
		(start 85.925 67.552)
		(end 86.748 67.552)
		(width 0.2)
		(layer "B.Cu")
		(net 2)
	)
	(segment
		(start 92.575 67.45)
		(end 91.85 67.45)
		(width 0.2)
		(layer "B.Cu")
		(net 2)
	)
	(segment
		(start 100.4 92.65)
		(end 99.8 92.65)
		(width 1)
		(layer "B.Cu")
		(net 2)
	)
	(segment
		(start 99 92.65)
		(end 96.85 92.65)
		(width 1)
		(layer "B.Cu")
		(net 2)
	)
	(segment
		(start 102.024946 90.931054)
		(end 102.024946 92.225054)
		(width 1)
		(layer "B.Cu")
		(net 2)
	)
	(segment
		(start 92.575 67.953)
		(end 92.575 67.45)
		(width 0.2)
		(layer "B.Cu")
		(net 2)
	)
	(segment
		(start 84.727 64.574)
		(end 84.182 64.574)
		(width 0.4)
		(layer "B.Cu")
		(net 2)
	)
	(segment
		(start 102.076 86.85)
		(end 102.056 86.87)
		(width 1.5)
		(layer "B.Cu")
		(net 2)
	)
	(segment
		(start 83.9 66.9)
		(end 83.9 66.5)
		(width 0.2)
		(layer "B.Cu")
		(net 2)
	)
	(segment
		(start 83.648 67.552)
		(end 82.925 67.552)
		(width 0.2)
		(layer "B.Cu")
		(net 2)
	)
	(segment
		(start 82.925 66.25)
		(end 82.4 66.25)
		(width 0.4)
		(layer "B.Cu")
		(net 2)
	)
	(segment
		(start 84.048 88.403)
		(end 83.976 88.475)
		(width 0.3)
		(layer "B.Cu")
		(net 2)
	)
	(segment
		(start 85.552 67.552)
		(end 85.5 67.5)
		(width 0.4)
		(layer "B.Cu")
		(net 2)
	)
	(segment
		(start 102.056 90.87)
		(end 102.056 90.9)
		(width 1.5)
		(layer "B.Cu")
		(net 2)
	)
	(segment
		(start 85.051 82.153)
		(end 83.953 82.153)
		(width 0.3)
		(layer "B.Cu")
		(net 2)
	)
	(segment
		(start 92.575 66.8)
		(end 91.6 66.8)
		(width 0.2)
		(layer "B.Cu")
		(net 2)
	)
	(segment
		(start 83.376 91.35)
		(end 82.856 91.87)
		(width 0.5)
		(layer "B.Cu")
		(net 2)
	)
	(segment
		(start 83.9 67.3)
		(end 83.648 67.552)
		(width 0.2)
		(layer "B.Cu")
		(net 2)
	)
	(segment
		(start 102.056 89.73)
		(end 102.056 90.83)
		(width 1.5)
		(layer "B.Cu")
		(net 2)
	)
	(segment
		(start 96.4 86.113)
		(end 96.266 85.979)
		(width 0.4)
		(layer "B.Cu")
		(net 2)
	)
	(segment
		(start 88.276 90.75)
		(end 88.976 91.45)
		(width 0.5)
		(layer "B.Cu")
		(net 2)
	)
	(segment
		(start 97.17 92.97)
		(end 96.15 91.95)
		(width 0.4)
		(layer "B.Cu")
		(net 2)
	)
	(segment
		(start 102.056 85.87)
		(end 102.056 86.83)
		(width 1.5)
		(layer "B.Cu")
		(net 2)
	)
	(segment
		(start 84.182 64.574)
		(end 83.608 64)
		(width 0.4)
		(layer "B.Cu")
		(net 2)
	)
	(segment
		(start 102.056 86.83)
		(end 102.076 86.85)
		(width 1.5)
		(layer "B.Cu")
		(net 2)
	)
	(segment
		(start 102.076 85.85)
		(end 102.056 85.87)
		(width 1.5)
		(layer "B.Cu")
		(net 2)
	)
	(segment
		(start 83.9 82.1)
		(end 83.9 82.15)
		(width 0.4)
		(layer "B.Cu")
		(net 2)
	)
	(segment
		(start 96.4 86.57)
		(end 97.92 86.57)
		(width 0.4)
		(layer "B.Cu")
		(net 2)
	)
	(segment
		(start 82.55 83.5)
		(end 82.55 83.5)
		(width 0.4)
		(layer "B.Cu")
		(net 2)
	)
	(segment
		(start 82.4 67.5)
		(end 82.45 67.55)
		(width 0.4)
		(layer "B.Cu")
		(net 2)
	)
	(segment
		(start 86.55 66.25)
		(end 86.9 66.6)
		(width 0.2)
		(layer "B.Cu")
		(net 2)
	)
	(segment
		(start 96.266 85.979)
		(end 96.266 85.344)
		(width 0.4)
		(layer "B.Cu")
		(net 2)
	)
	(segment
		(start 92.526 68.002)
		(end 92.526 67.975)
		(width 0.2)
		(layer "B.Cu")
		(net 2)
	)
	(segment
		(start 102.076 90.85)
		(end 102.056 90.87)
		(width 1.5)
		(layer "B.Cu")
		(net 2)
	)
	(segment
		(start 101.6 92.65)
		(end 100.4 92.65)
		(width 1)
		(layer "B.Cu")
		(net 2)
	)
	(segment
		(start 90.3328 81.85)
		(end 89.2 81.85)
		(width 0.2)
		(layer "B.Cu")
		(net 2)
	)
	(segment
		(start 88.63 82.42)
		(end 88.575 82.42)
		(width 0.2)
		(layer "B.Cu")
		(net 2)
	)
	(segment
		(start 91.852 66.148)
		(end 91.75 66.25)
		(width 0.2)
		(layer "B.Cu")
		(net 2)
	)
	(segment
		(start 96.4 88.57)
		(end 98.151 88.57)
		(width 0.3)
		(layer "B.Cu")
		(net 2)
	)
	(segment
		(start 97.92 86.57)
		(end 97.95 86.6)
		(width 0.4)
		(layer "B.Cu")
		(net 2)
	)
	(segment
		(start 96.85 92.65)
		(end 96.15 91.95)
		(width 1)
		(layer "B.Cu")
		(net 2)
	)
	(segment
		(start 83.9 66.4)
		(end 83.75 66.25)
		(width 0.2)
		(layer "B.Cu")
		(net 2)
	)
	(segment
		(start 83.9 82.15)
		(end 83.9 82.15)
		(width 0.4)
		(layer "B.Cu")
		(net 2)
	)
	(segment
		(start 85.925 66.25)
		(end 85.55 66.25)
		(width 0.4)
		(layer "B.Cu")
		(net 2)
	)
	(segment
		(start 83.225 82.8)
		(end 83.225 82.825)
		(width 0.4)
		(layer "B.Cu")
		(net 2)
	)
	(segment
		(start 83.9 66.5)
		(end 83.9 66.4)
		(width 0.2)
		(layer "B.Cu")
		(net 2)
	)
	(segment
		(start 82.856 91.87)
		(end 82.476 91.87)
		(width 0.5)
		(layer "B.Cu")
		(net 2)
	)
	(segment
		(start 99.8 92.65)
		(end 99 92.65)
		(width 1)
		(layer "B.Cu")
		(net 2)
	)
	(segment
		(start 86.002761 79.149333)
		(end 86.529333 79.149333)
		(width 0.2)
		(layer "B.Cu")
		(net 2)
	)
	(segment
		(start 102.056 87.87)
		(end 102.076 87.85)
		(width 1.5)
		(layer "B.Cu")
		(net 2)
	)
	(segment
		(start 89.27 88.62)
		(end 88.576 88.62)
		(width 0.4)
		(layer "B.Cu")
		(net 2)
	)
	(segment
		(start 85.925 66.9)
		(end 85.5 66.9)
		(width 0.4)
		(layer "B.Cu")
		(net 2)
	)
	(segment
		(start 102.056 87.83)
		(end 102.076 87.85)
		(width 1.5)
		(layer "B.Cu")
		(net 2)
	)
	(segment
		(start 96.4 86.57)
		(end 96.4 86.113)
		(width 0.4)
		(layer "B.Cu")
		(net 2)
	)
	(segment
		(start 92.331 68.197)
		(end 92.526 68.002)
		(width 0.2)
		(layer "B.Cu")
		(net 2)
	)
	(segment
		(start 82.452 67.552)
		(end 82.45 67.55)
		(width 0.4)
		(layer "B.Cu")
		(net 2)
	)
	(segment
		(start 86.748 67.552)
		(end 86.9 67.4)
		(width 0.2)
		(layer "B.Cu")
		(net 2)
	)
	(segment
		(start 101.976 89.65)
		(end 102.056 89.73)
		(width 1.5)
		(layer "B.Cu")
		(net 2)
	)
	(segment
		(start 92.575 65.620183)
		(end 92.575 66.148)
		(width 0.4)
		(layer "B.Cu")
		(net 2)
	)
	(segment
		(start 86.9 66.6)
		(end 86.9 66.9)
		(width 0.2)
		(layer "B.Cu")
		(net 2)
	)
	(segment
		(start 83.9 66.9)
		(end 83.9 67.3)
		(width 0.2)
		(layer "B.Cu")
		(net 2)
	)
	(segment
		(start 92.554817 65.6)
		(end 92.575 65.620183)
		(width 0.4)
		(layer "B.Cu")
		(net 2)
	)
	(segment
		(start 89.2 81.85)
		(end 88.63 82.42)
		(width 0.2)
		(layer "B.Cu")
		(net 2)
	)
	(segment
		(start 90.725 81.4578)
		(end 90.3328 81.85)
		(width 0.2)
		(layer "B.Cu")
		(net 2)
	)
	(segment
		(start 92.331 68.6)
		(end 92.331 68.197)
		(width 0.2)
		(layer "B.Cu")
		(net 2)
	)
	(segment
		(start 92.526 67.975)
		(end 92.553 67.975)
		(width 0.2)
		(layer "B.Cu")
		(net 2)
	)
	(segment
		(start 91.675 64.574)
		(end 92.249 64)
		(width 0.4)
		(layer "B.Cu")
		(net 2)
	)
	(segment
		(start 85.052 88.403)
		(end 84.048 88.403)
		(width 0.3)
		(layer "B.Cu")
		(net 2)
	)
	(segment
		(start 85.55 66.25)
		(end 85.5 66.3)
		(width 0.4)
		(layer "B.Cu")
		(net 2)
	)
	(segment
		(start 83.25 82.8)
		(end 83.225 82.8)
		(width 0.4)
		(layer "B.Cu")
		(net 2)
	)
	(segment
		(start 83.376 89.075)
		(end 83.376 91.35)
		(width 0.5)
		(layer "B.Cu")
		(net 2)
	)
	(segment
		(start 92.553 67.975)
		(end 92.575 67.953)
		(width 0.2)
		(layer "B.Cu")
		(net 2)
	)
	(segment
		(start 82.925 66.9)
		(end 83.9 66.9)
		(width 0.2)
		(layer "B.Cu")
		(net 2)
	)
	(segment
		(start 82.4 67.55)
		(end 82.4 67.5)
		(width 0.4)
		(layer "B.Cu")
		(net 2)
	)
	(segment
		(start 83.75 66.25)
		(end 82.925 66.25)
		(width 0.2)
		(layer "B.Cu")
		(net 2)
	)
	(segment
		(start 82.55 82.9)
		(end 82.55 83.5)
		(width 0.4)
		(layer "B.Cu")
		(net 2)
	)
	(segment
		(start 102.056 85.3)
		(end 102.056 85.83)
		(width 1.5)
		(layer "B.Cu")
		(net 2)
	)
	(segment
		(start 102.053554 89.046446)
		(end 102.056 89.044)
		(width 1.5)
		(layer "B.Cu")
		(net 2)
	)
	(segment
		(start 92.575 66.148)
		(end 91.852 66.148)
		(width 0.2)
		(layer "B.Cu")
		(net 2)
	)
	(segment
		(start 102.056 90.83)
		(end 102.076 90.85)
		(width 1.5)
		(layer "B.Cu")
		(net 2)
	)
	(segment
		(start 85.925 66.9)
		(end 86.9 66.9)
		(width 0.2)
		(layer "B.Cu")
		(net 2)
	)
	(segment
		(start 102.056 89.048892)
		(end 102.056 89.57)
		(width 1.5)
		(layer "B.Cu")
		(net 2)
	)
	(segment
		(start 83.9 82.15)
		(end 83.9 82.675)
		(width 0.4)
		(layer "B.Cu")
		(net 2)
	)
	(segment
		(start 102.024946 92.225054)
		(end 101.6 92.65)
		(width 1)
		(layer "B.Cu")
		(net 2)
	)
	(segment
		(start 85.925 67.552)
		(end 85.552 67.552)
		(width 0.4)
		(layer "B.Cu")
		(net 2)
	)
	(segment
		(start 82.925 67.552)
		(end 82.452 67.552)
		(width 0.4)
		(layer "B.Cu")
		(net 2)
	)
	(segment
		(start 91.129 64.574)
		(end 91.675 64.574)
		(width 0.4)
		(layer "B.Cu")
		(net 2)
	)
	(segment
		(start 98.151 88.57)
		(end 98.181 88.6)
		(width 0.3)
		(layer "B.Cu")
		(net 2)
	)
	(segment
		(start 102.056 85.83)
		(end 102.076 85.85)
		(width 1.5)
		(layer "B.Cu")
		(net 2)
	)
	(segment
		(start 82.925 66.9)
		(end 82.4 66.9)
		(width 0.4)
		(layer "B.Cu")
		(net 2)
	)
	(segment
		(start 102.056 89.044)
		(end 102.056 87.87)
		(width 1.5)
		(layer "B.Cu")
		(net 2)
	)
	(segment
		(start 82.45 67.55)
		(end 82.4 67.55)
		(width 0.4)
		(layer "B.Cu")
		(net 2)
	)
	(segment
		(start 102.053554 89.046446)
		(end 102.056 89.048892)
		(width 1.5)
		(layer "B.Cu")
		(net 2)
	)
	(segment
		(start 83.953 82.153)
		(end 83.9 82.1)
		(width 0.3)
		(layer "B.Cu")
		(net 2)
	)
	(segment
		(start 86.529333 79.149333)
		(end 87.4 80.02)
		(width 0.2)
		(layer "B.Cu")
		(net 2)
	)
	(segment
		(start 82.925 66.25)
		(end 82.925 67.552)
		(width 0.3)
		(layer "B.Cu")
		(net 2)
	)
	(segment
		(start 83.976 88.475)
		(end 83.376 89.075)
		(width 0.5)
		(layer "B.Cu")
		(net 2)
	)
	(segment
		(start 97.6 92.97)
		(end 97.17 92.97)
		(width 0.4)
		(layer "B.Cu")
		(net 2)
	)
	(segment
		(start 92.575 66.148)
		(end 92.575 67.45)
		(width 0.2)
		(layer "B.Cu")
		(net 2)
	)
	(segment
		(start 82.75 80.15)
		(end 82.45 80.15)
		(width 0.25)
		(layer "F.Cu")
		(net 3)
	)
	(segment
		(start 83.696 78.525)
		(end 83.696 79.204)
		(width 0.25)
		(layer "F.Cu")
		(net 3)
	)
	(segment
		(start 83.696 79.204)
		(end 82.75 80.15)
		(width 0.25)
		(layer "F.Cu")
		(net 3)
	)
	(segment
		(start 100.73 86.6)
		(end 100.73 87.6)
		(width 0.2)
		(layer "F.Cu")
		(net 4)
	)
	(segment
		(start 102.151 89.851)
		(end 102.151 90.35)
		(width 0.2)
		(layer "F.Cu")
		(net 5)
	)
	(segment
		(start 100.777 84.577)
		(end 101.05 84.85)
		(width 0.2)
		(layer "F.Cu")
		(net 5)
	)
	(segment
		(start 98.45 90.1)
		(end 98.1 89.75)
		(width 0.3)
		(layer "F.Cu")
		(net 5)
	)
	(segment
		(start 100.977 85.577)
		(end 101.05 85.65)
		(width 0.2)
		(layer "F.Cu")
		(net 5)
	)
	(segment
		(start 101.05 84.85)
		(end 101.05 85.65)
		(width 0.2)
		(layer "F.Cu")
		(net 5)
	)
	(segment
		(start 101.05 85.65)
		(end 101.25 85.85)
		(width 0.2)
		(layer "F.Cu")
		(net 5)
	)
	(segment
		(start 101.25 88.95)
		(end 102.151 89.851)
		(width 0.2)
		(layer "F.Cu")
		(net 5)
	)
	(segment
		(start 101.25 85.85)
		(end 101.25 88.65)
		(width 0.2)
		(layer "F.Cu")
		(net 5)
	)
	(segment
		(start 91.851 105.57)
		(end 91.851 104.875)
		(width 0.3)
		(layer "F.Cu")
		(net 5)
	)
	(segment
		(start 99.40078 90.1)
		(end 98.45 90.1)
		(width 0.3)
		(layer "F.Cu")
		(net 5)
	)
	(segment
		(start 101.25 88.65)
		(end 101.2 88.6)
		(width 0.2)
		(layer "F.Cu")
		(net 5)
	)
	(segment
		(start 101.2 88.6)
		(end 100.73 88.6)
		(width 0.2)
		(layer "F.Cu")
		(net 5)
	)
	(segment
		(start 99.435698 90.134918)
		(end 99.40078 90.1)
		(width 0.3)
		(layer "F.Cu")
		(net 5)
	)
	(segment
		(start 101.25 88.65)
		(end 101.25 88.95)
		(width 0.2)
		(layer "F.Cu")
		(net 5)
	)
	(segment
		(start 102.151 90.35)
		(end 102.776 90.975)
		(width 0.2)
		(layer "F.Cu")
		(net 5)
	)
	(segment
		(start 89.676 105.05)
		(end 91.331 105.05)
		(width 0.125)
		(layer "F.Cu")
		(net 5)
	)
	(segment
		(start 91.851 104.875)
		(end 91.876 104.85)
		(width 0.3)
		(layer "F.Cu")
		(net 5)
	)
	(segment
		(start 102.776 94.8)
		(end 102.051 95.525)
		(width 0.2)
		(layer "F.Cu")
		(net 5)
	)
	(segment
		(start 100.48 85.577)
		(end 100.977 85.577)
		(width 0.2)
		(layer "F.Cu")
		(net 5)
	)
	(segment
		(start 102.776 90.975)
		(end 102.776 94.8)
		(width 0.2)
		(layer "F.Cu")
		(net 5)
	)
	(segment
		(start 98.1 89.75)
		(end 98.1 89.48)
		(width 0.3)
		(layer "F.Cu")
		(net 5)
	)
	(segment
		(start 91.331 105.05)
		(end 91.851 105.57)
		(width 0.125)
		(layer "F.Cu")
		(net 5)
	)
	(segment
		(start 100.48 84.577)
		(end 100.777 84.577)
		(width 0.2)
		(layer "F.Cu")
		(net 5)
	)
	(via
		(at 91.876 97.15)
		(size 0.55)
		(drill 0.25)
		(layers "F.Cu" "B.Cu")
		(free yes)
		(net 5)
	)
	(via
		(at 87.276 94.65)
		(size 0.55)
		(drill 0.25)
		(layers "F.Cu" "B.Cu")
		(free yes)
		(net 5)
	)
	(via
		(at 85.076 90.45)
		(size 0.55)
		(drill 0.25)
		(layers "F.Cu" "B.Cu")
		(net 5)
	)
	(via
		(at 97.576 94.575)
		(size 0.55)
		(drill 0.25)
		(layers "F.Cu" "B.Cu")
		(free yes)
		(net 5)
	)
	(via
		(at 83.776 84.35)
		(size 0.55)
		(drill 0.25)
		(layers "F.Cu" "B.Cu")
		(net 5)
	)
	(via
		(at 99.326 96.35)
		(size 0.55)
		(drill 0.25)
		(layers "F.Cu" "B.Cu")
		(net 5)
	)
	(via
		(at 88.876 97.15)
		(size 0.55)
		(drill 0.25)
		(layers "F.Cu" "B.Cu")
		(free yes)
		(net 5)
	)
	(via
		(at 92 95.25)
		(size 0.55)
		(drill 0.25)
		(layers "F.Cu" "B.Cu")
		(free yes)
		(net 5)
	)
	(via
		(at 88.176 97.15)
		(size 0.55)
		(drill 0.25)
		(layers "F.Cu" "B.Cu")
		(free yes)
		(net 5)
	)
	(via
		(at 89.357531 87.977454)
		(size 0.55)
		(drill 0.25)
		(layers "F.Cu" "B.Cu")
		(net 5)
	)
	(via
		(at 85.976 95.25)
		(size 0.55)
		(drill 0.25)
		(layers "F.Cu" "B.Cu")
		(free yes)
		(net 5)
	)
	(via
		(at 85.176 95.25)
		(size 0.55)
		(drill 0.25)
		(layers "F.Cu" "B.Cu")
		(free yes)
		(net 5)
	)
	(via
		(at 87.276 93.85)
		(size 0.55)
		(drill 0.25)
		(layers "F.Cu" "B.Cu")
		(free yes)
		(net 5)
	)
	(via
		(at 82.376 84.35)
		(size 0.55)
		(drill 0.25)
		(layers "F.Cu" "B.Cu")
		(net 5)
	)
	(via
		(at 97.826 96.35)
		(size 0.55)
		(drill 0.25)
		(layers "F.Cu" "B.Cu")
		(net 5)
	)
	(via
		(at 91.876 104.85)
		(size 0.55)
		(drill 0.25)
		(layers "F.Cu" "B.Cu")
		(net 5)
	)
	(via
		(at 90.476 97.15)
		(size 0.55)
		(drill 0.25)
		(layers "F.Cu" "B.Cu")
		(free yes)
		(net 5)
	)
	(via
		(at 83.076 84.35)
		(size 0.55)
		(drill 0.25)
		(layers "F.Cu" "B.Cu")
		(net 5)
	)
	(via
		(at 96.5 97.25)
		(size 0.55)
		(drill 0.25)
		(layers "F.Cu" "B.Cu")
		(free yes)
		(net 5)
	)
	(via
		(at 82.276 84.95)
		(size 0.55)
		(drill 0.25)
		(layers "F.Cu" "B.Cu")
		(net 5)
	)
	(via
		(at 94.276 97.15)
		(size 0.55)
		(drill 0.25)
		(layers "F.Cu" "B.Cu")
		(free yes)
		(net 5)
	)
	(via
		(at 101 96.25)
		(size 0.55)
		(drill 0.25)
		(layers "F.Cu" "B.Cu")
		(free yes)
		(net 5)
	)
	(via
		(at 91.176 97.15)
		(size 0.55)
		(drill 0.25)
		(layers "F.Cu" "B.Cu")
		(free yes)
		(net 5)
	)
	(via
		(at 83.476 84.95)
		(size 0.55)
		(drill 0.25)
		(layers "F.Cu" "B.Cu")
		(net 5)
	)
	(via
		(at 95.5 97.25)
		(size 0.55)
		(drill 0.25)
		(layers "F.Cu" "B.Cu")
		(free yes)
		(net 5)
	)
	(via
		(at 96.326 96.35)
		(size 0.55)
		(drill 0.25)
		(layers "F.Cu" "B.Cu")
		(net 5)
	)
	(via
		(at 100.076 96.35)
		(size 0.55)
		(drill 0.25)
		(layers "F.Cu" "B.Cu")
		(net 5)
	)
	(via
		(at 93.576 97.15)
		(size 0.55)
		(drill 0.25)
		(layers "F.Cu" "B.Cu")
		(free yes)
		(net 5)
	)
	(via
		(at 88 95.25)
		(size 0.55)
		(drill 0.25)
		(layers "F.Cu" "B.Cu")
		(free yes)
		(net 5)
	)
	(via
		(at 100.803409 88.673409)
		(size 0.55)
		(drill 0.25)
		(layers "F.Cu" "B.Cu")
		(net 5)
	)
	(via
		(at 95.151 95.4)
		(size 0.55)
		(drill 0.25)
		(layers "F.Cu" "B.Cu")
		(free yes)
		(net 5)
	)
	(via
		(at 98.576 96.35)
		(size 0.55)
		(drill 0.25)
		(layers "F.Cu" "B.Cu")
		(net 5)
	)
	(via
		(at 97.076 96.35)
		(size 0.55)
		(drill 0.25)
		(layers "F.Cu" "B.Cu")
		(net 5)
	)
	(via
		(at 92.776 97.15)
		(size 0.55)
		(drill 0.25)
		(layers "F.Cu" "B.Cu")
		(free yes)
		(net 5)
	)
	(via
		(at 84.476 90.45)
		(size 0.55)
		(drill 0.25)
		(layers "F.Cu" "B.Cu")
		(free yes)
		(net 5)
	)
	(via
		(at 95.576 96.35)
		(size 0.55)
		(drill 0.25)
		(layers "F.Cu" "B.Cu")
		(net 5)
	)
	(via
		(at 82.876 84.95)
		(size 0.55)
		(drill 0.25)
		(layers "F.Cu" "B.Cu")
		(net 5)
	)
	(via
		(at 101.826 96.25)
		(size 0.55)
		(drill 0.25)
		(layers "F.Cu" "B.Cu")
		(free yes)
		(net 5)
	)
	(via
		(at 90 95.25)
		(size 0.55)
		(drill 0.25)
		(layers "F.Cu" "B.Cu")
		(free yes)
		(net 5)
	)
	(via
		(at 99.435698 90.134918)
		(size 0.55)
		(drill 0.25)
		(layers "F.Cu" "B.Cu")
		(net 5)
	)
	(via
		(at 89.576 97.15)
		(size 0.55)
		(drill 0.25)
		(layers "F.Cu" "B.Cu")
		(free yes)
		(net 5)
	)
	(via
		(at 93.45 94.8)
		(size 0.55)
		(drill 0.25)
		(layers "F.Cu" "B.Cu")
		(free yes)
		(net 5)
	)
	(segment
		(start 82.376 84.35)
		(end 83.076 84.35)
		(width 0.4)
		(layer "B.Cu")
		(net 5)
	)
	(segment
		(start 83.776 83.624)
		(end 83.9 83.5)
		(width 0.4)
		(layer "B.Cu")
		(net 5)
	)
	(segment
		(start 84.251 83.149)
		(end 85.051 83.149)
		(width 0.2)
		(layer "B.Cu")
		(net 5)
	)
	(segment
		(start 84.777 89.399)
		(end 85.052 89.399)
		(width 0.3)
		(layer "B.Cu")
		(net 5)
	)
	(segment
		(start 85.37 84.25)
		(end 84.65 84.25)
		(width 0.2)
		(layer "B.Cu")
		(net 5)
	)
	(segment
		(start 89.357531 87.226531)
		(end 88.351 86.22)
		(width 0.2)
		(layer "B.Cu")
		(net 5)
	)
	(segment
		(start 83.776 84.35)
		(end 83.776 83.624)
		(width 0.4)
		(layer "B.Cu")
		(net 5)
	)
	(segment
		(start 99.435698 90.064302)
		(end 99.435698 90.134918)
		(width 0.3)
		(layer "B.Cu")
		(net 5)
	)
	(segment
		(start 83.076 84.35)
		(end 83.75 84.35)
		(width 0.4)
		(layer "B.Cu")
		(net 5)
	)
	(segment
		(start 83.9 83.5)
		(end 84.251 83.149)
		(width 0.2)
		(layer "B.Cu")
		(net 5)
	)
	(segment
		(start 83.75 84.35)
		(end 83.776 84.35)
		(width 0.4)
		(layer "B.Cu")
		(net 5)
	)
	(segment
		(start 82.35 84.35)
		(end 82.326 84.35)
		(width 0.4)
		(layer "B.Cu")
		(net 5)
	)
	(segment
		(start 82.326 84.35)
		(end 82.376 84.35)
		(width 0.4)
		(layer "B.Cu")
		(net 5)
	)
	(segment
		(start 100.803409 88.673409)
		(end 100.803409 88.696591)
		(width 0.3)
		(layer "B.Cu")
		(net 5)
	)
	(segment
		(start 84.65 84.25)
		(end 83.9 83.5)
		(width 0.2)
		(layer "B.Cu")
		(net 5)
	)
	(segment
		(start 100.803409 88.696591)
		(end 99.435698 90.064302)
		(width 0.3)
		(layer "B.Cu")
		(net 5)
	)
	(segment
		(start 89.357531 87.977454)
		(end 89.357531 87.226531)
		(width 0.2)
		(layer "B.Cu")
		(net 5)
	)
	(segment
		(start 91.876 104.85)
		(end 92.476 104.25)
		(width 0.3)
		(layer "In2.Cu")
		(net 5)
	)
	(segment
		(start 89.230077 87.85)
		(end 86.476 87.85)
		(width 0.2)
		(layer "In2.Cu")
		(net 5)
	)
	(segment
		(start 92.476 104.25)
		(end 92.476 99.15)
		(width 0.3)
		(layer "In2.Cu")
		(net 5)
	)
	(segment
		(start 89.357531 87.977454)
		(end 89.230077 87.85)
		(width 0.2)
		(layer "In2.Cu")
		(net 5)
	)
	(segment
		(start 92.776 98.85)
		(end 92.776 97.15)
		(width 0.3)
		(layer "In2.Cu")
		(net 5)
	)
	(segment
		(start 92.476 99.15)
		(end 92.776 98.85)
		(width 0.3)
		(layer "In2.Cu")
		(net 5)
	)
	(segment
		(start 86.506 77.545)
		(end 87.326 76.725)
		(width 0.2)
		(layer "F.Cu")
		(net 6)
	)
	(segment
		(start 91.076 78.375)
		(end 91.151 78.45)
		(width 1)
		(layer "F.Cu")
		(net 6)
	)
	(segment
		(start 88.185 72.15)
		(end 88.635 71.7)
		(width 0.2)
		(layer "F.Cu")
		(net 6)
	)
	(segment
		(start 90.85 72.099)
		(end 90.85 71.75)
		(width 0.125)
		(layer "F.Cu")
		(net 6)
	)
	(segment
		(start 89.05 76.4)
		(end 89.276 76.45)
		(width 0.2)
		(layer "F.Cu")
		(net 6)
	)
	(segment
		(start 88.626 76.4)
		(end 88.676 76.45)
		(width 0.2)
		(layer "F.Cu")
		(net 6)
	)
	(segment
		(start 88.676 76.45)
		(end 88.726 76.4)
		(width 0.2)
		(layer "F.Cu")
		(net 6)
	)
	(segment
		(start 90.85 71.75)
		(end 90.6 71.7)
		(width 0.125)
		(layer "F.Cu")
		(net 6)
	)
	(segment
		(start 89.154 70.866)
		(end 89.2 70.82)
		(width 0.125)
		(layer "F.Cu")
		(net 6)
	)
	(segment
		(start 89.2 70.82)
		(end 89.2 71)
		(width 0.125)
		(layer "F.Cu")
		(net 6)
	)
	(segment
		(start 88.92 71.7)
		(end 88.92 71.28)
		(width 0.2)
		(layer "F.Cu")
		(net 6)
	)
	(segment
		(start 91.426 71.574)
		(end 91.3 71.7)
		(width 0.2)
		(layer "F.Cu")
		(net 6)
	)
	(segment
		(start 87.538 72.15)
		(end 88.185 72.15)
		(width 0.2)
		(layer "F.Cu")
		(net 6)
	)
	(segment
		(start 91.076 77.65)
		(end 91.076 78.375)
		(width 1)
		(layer "F.Cu")
		(net 6)
	)
	(segment
		(start 87.326 76.55)
		(end 87.476 76.4)
		(width 0.2)
		(layer "F.Cu")
		(net 6)
	)
	(segment
		(start 87.476 76.4)
		(end 88.626 76.4)
		(width 0.2)
		(layer "F.Cu")
		(net 6)
	)
	(segment
		(start 89.276 76.45)
		(end 89.15 76.4)
		(width 0.2)
		(layer "F.Cu")
		(net 6)
	)
	(segment
		(start 98.488125 72.382125)
		(end 98.426 72.382125)
		(width 0.3)
		(layer "F.Cu")
		(net 6)
	)
	(segment
		(start 88.726 76.4)
		(end 89.05 76.4)
		(width 0.2)
		(layer "F.Cu")
		(net 6)
	)
	(segment
		(start 86.506 77.575)
		(end 86.506 77.545)
		(width 0.2)
		(layer "F.Cu")
		(net 6)
	)
	(segment
		(start 90.6 71.7)
		(end 90.8 71.7)
		(width 0.125)
		(layer "F.Cu")
		(net 6)
	)
	(segment
		(start 92.001 71.65)
		(end 91.925 71.574)
		(width 0.2)
		(layer "F.Cu")
		(net 6)
	)
	(segment
		(start 92.077 71.574)
		(end 92.001 71.65)
		(width 0.2)
		(layer "F.Cu")
		(net 6)
	)
	(segment
		(start 91.925 71.574)
		(end 91.426 71.574)
		(width 0.2)
		(layer "F.Cu")
		(net 6)
	)
	(segment
		(start 88.92 71.28)
		(end 89.2 71)
		(width 0.2)
		(layer "F.Cu")
		(net 6)
	)
	(segment
		(start 88.635 71.7)
		(end 88.92 71.7)
		(width 0.2)
		(layer "F.Cu")
		(net 6)
	)
	(segment
		(start 97.976 71.932125)
		(end 97.976 71.87)
		(width 0.3)
		(layer "F.Cu")
		(net 6)
	)
	(segment
		(start 89.15 76.4)
		(end 89.1 76.4)
		(width 0.2)
		(layer "F.Cu")
		(net 6)
	)
	(segment
		(start 87.326 76.725)
		(end 87.326 76.55)
		(width 0.2)
		(layer "F.Cu")
		(net 6)
	)
	(segment
		(start 98.426 72.382125)
		(end 97.976 71.932125)
		(width 0.3)
		(layer "F.Cu")
		(net 6)
	)
	(via
		(at 91.676 74.65)
		(size 0.45)
		(drill 0.2)
		(layers "F.Cu" "B.Cu")
		(free yes)
		(net 6)
	)
	(via
		(at 91.076 76.45)
		(size 0.45)
		(drill 0.2)
		(layers "F.Cu" "B.Cu")
		(free yes)
		(net 6)
	)
	(via
		(at 89.6 63.3)
		(size 0.45)
		(drill 0.2)
		(layers "F.Cu" "B.Cu")
		(free yes)
		(net 6)
	)
	(via
		(at 89.276 76.45)
		(size 0.45)
		(drill 0.2)
		(layers "F.Cu" "B.Cu")
		(net 6)
	)
	(via
		(at 91.076 77.05)
		(size 0.45)
		(drill 0.2)
		(layers "F.Cu" "B.Cu")
		(free yes)
		(net 6)
	)
	(via
		(at 90.6 71.7)
		(size 0.55)
		(drill 0.25)
		(layers "F.Cu" "B.Cu")
		(net 6)
	)
	(via
		(at 89.351 75.15)
		(size 0.45)
		(drill 0.2)
		(layers "F.Cu" "B.Cu")
		(free yes)
		(net 6)
	)
	(via
		(at 89.2 71)
		(size 0.55)
		(drill 0.25)
		(layers "F.Cu" "B.Cu")
		(net 6)
	)
	(via
		(at 87.8 62.5)
		(size 0.45)
		(drill 0.2)
		(layers "F.Cu" "B.Cu")
		(free yes)
		(net 6)
	)
	(via
		(at 89.6 62.5)
		(size 0.45)
		(drill 0.2)
		(layers "F.Cu" "B.Cu")
		(free yes)
		(net 6)
	)
	(via
		(at 91.276 69.25)
		(size 0.55)
		(drill 0.25)
		(layers "F.Cu" "B.Cu")
		(free yes)
		(net 6)
	)
	(via
		(at 91.276 72.75)
		(size 0.45)
		(drill 0.2)
		(layers "F.Cu" "B.Cu")
		(free yes)
		(net 6)
	)
	(via
		(at 89.876 68.55)
		(size 0.55)
		(drill 0.25)
		(layers "F.Cu" "B.Cu")
		(free yes)
		(net 6)
	)
	(via
		(at 98.426 72.382125)
		(size 0.45)
		(drill 0.2)
		(layers "F.Cu" "B.Cu")
		(net 6)
	)
	(via
		(at 89.976 75.1)
		(size 0.45)
		(drill 0.2)
		(layers "F.Cu" "B.Cu")
		(free yes)
		(net 6)
	)
	(via
		(at 92.001 71.65)
		(size 0.55)
		(drill 0.25)
		(layers "F.Cu" "B.Cu")
		(net 6)
	)
	(via
		(at 90.676 73.35)
		(size 0.45)
		(drill 0.2)
		(layers "F.Cu" "B.Cu")
		(free yes)
		(net 6)
	)
	(via
		(at 90.676 73.95)
		(size 0.45)
		(drill 0.2)
		(layers "F.Cu" "B.Cu")
		(free yes)
		(net 6)
	)
	(via
		(at 91.3 70.3)
		(size 0.55)
		(drill 0.25)
		(layers "F.Cu" "B.Cu")
		(free yes)
		(net 6)
	)
	(via
		(at 91.826 75.225)
		(size 0.45)
		(drill 0.2)
		(layers "F.Cu" "B.Cu")
		(free yes)
		(net 6)
	)
	(via
		(at 91.876 72.75)
		(size 0.45)
		(drill 0.2)
		(layers "F.Cu" "B.Cu")
		(free yes)
		(net 6)
	)
	(via
		(at 91.3 71)
		(size 0.55)
		(drill 0.25)
		(layers "F.Cu" "B.Cu")
		(free yes)
		(net 6)
	)
	(via
		(at 91.226 75.225)
		(size 0.45)
		(drill 0.2)
		(layers "F.Cu" "B.Cu")
		(free yes)
		(net 6)
	)
	(via
		(at 89.087414 74.587385)
		(size 0.45)
		(drill 0.2)
		(layers "F.Cu" "B.Cu")
		(free yes)
		(net 6)
	)
	(via
		(at 91.226 75.775)
		(size 0.45)
		(drill 0.2)
		(layers "F.Cu" "B.Cu")
		(free yes)
		(net 6)
	)
	(via
		(at 90.6 69.25)
		(size 0.55)
		(drill 0.25)
		(layers "F.Cu" "B.Cu")
		(free yes)
		(net 6)
	)
	(via
		(at 86.9 62.5)
		(size 0.45)
		(drill 0.2)
		(layers "F.Cu" "B.Cu")
		(free yes)
		(net 6)
	)
	(via
		(at 86 63.3)
		(size 0.45)
		(drill 0.2)
		(layers "F.Cu" "B.Cu")
		(free yes)
		(net 6)
	)
	(via
		(at 91.076 74.65)
		(size 0.45)
		(drill 0.2)
		(layers "F.Cu" "B.Cu")
		(free yes)
		(net 6)
	)
	(via
		(at 91.076 77.65)
		(size 0.45)
		(drill 0.2)
		(layers "F.Cu" "B.Cu")
		(free yes)
		(net 6)
	)
	(via
		(at 89.9 69.25)
		(size 0.55)
		(drill 0.25)
		(layers "F.Cu" "B.Cu")
		(free yes)
		(net 6)
	)
	(via
		(at 90.476 76.45)
		(size 0.45)
		(drill 0.2)
		(layers "F.Cu" "B.Cu")
		(free yes)
		(net 6)
	)
	(via
		(at 90.6 71)
		(size 0.55)
		(drill 0.25)
		(layers "F.Cu" "B.Cu")
		(free yes)
		(net 6)
	)
	(via
		(at 89.876 76.45)
		(size 0.45)
		(drill 0.2)
		(layers "F.Cu" "B.Cu")
		(free yes)
		(net 6)
	)
	(via
		(at 87.8 63.3)
		(size 0.45)
		(drill 0.2)
		(layers "F.Cu" "B.Cu")
		(free yes)
		(net 6)
	)
	(via
		(at 91.3 71.7)
		(size 0.55)
		(drill 0.25)
		(layers "F.Cu" "B.Cu")
		(net 6)
	)
	(via
		(at 86.9 63.3)
		(size 0.45)
		(drill 0.2)
		(layers "F.Cu" "B.Cu")
		(free yes)
		(net 6)
	)
	(via
		(at 88.676 76.45)
		(size 0.45)
		(drill 0.2)
		(layers "F.Cu" "B.Cu")
		(net 6)
	)
	(via
		(at 90.676 72.75)
		(size 0.45)
		(drill 0.2)
		(layers "F.Cu" "B.Cu")
		(free yes)
		(net 6)
	)
	(via
		(at 90.601 68.55)
		(size 0.55)
		(drill 0.25)
		(layers "F.Cu" "B.Cu")
		(free yes)
		(net 6)
	)
	(via
		(at 90.476 74.65)
		(size 0.45)
		(drill 0.2)
		(layers "F.Cu" "B.Cu")
		(free yes)
		(net 6)
	)
	(via
		(at 88.7 62.5)
		(size 0.45)
		(drill 0.2)
		(layers "F.Cu" "B.Cu")
		(free yes)
		(net 6)
	)
	(via
		(at 89.9 70.3)
		(size 0.55)
		(drill 0.25)
		(layers "F.Cu" "B.Cu")
		(free yes)
		(net 6)
	)
	(via
		(at 88.676 75.85)
		(size 0.45)
		(drill 0.2)
		(layers "F.Cu" "B.Cu")
		(free yes)
		(net 6)
	)
	(via
		(at 88.7 63.3)
		(size 0.45)
		(drill 0.2)
		(layers "F.Cu" "B.Cu")
		(free yes)
		(net 6)
	)
	(segment
		(start 90.327 67.35)
		(end 90.427 67.45)
		(width 0.5)
		(layer "B.Cu")
		(net 6)
	)
	(segment
		(start 91.15 71.85)
		(end 91.3 71.7)
		(width 0.125)
		(layer "B.Cu")
		(net 6)
	)
	(segment
		(start 90.95 71.85)
		(end 91.15 71.85)
		(width 0.125)
		(layer "B.Cu")
		(net 6)
	)
	(segment
		(start 90.8 71.7)
		(end 90.95 71.85)
		(width 0.125)
		(layer "B.Cu")
		(net 6)
	)
	(segment
		(start 90.327 64.574)
		(end 90.327 67.35)
		(width 0.5)
		(layer "B.Cu")
		(net 6)
	)
	(segment
		(start 97.458125 73.35)
		(end 98.426 72.382125)
		(width 0.3)
		(layer "B.Cu")
		(net 6)
	)
	(segment
		(start 90.676 73.35)
		(end 97.458125 73.35)
		(width 0.3)
		(layer "B.Cu")
		(net 6)
	)
	(segment
		(start 90.427 67.45)
		(end 90.627 67.45)
		(width 0.5)
		(layer "B.Cu")
		(net 6)
	)
	(segment
		(start 86.576 78.45)
		(end 87.812 77.214)
		(width 0.3)
		(layer "F.Cu")
		(net 7)
	)
	(segment
		(start 84.65 77.5)
		(end 84.7 77.55)
		(width 0.3)
		(layer "F.Cu")
		(net 7)
	)
	(segment
		(start 86.392594 78.45)
		(end 86.576 78.45)
		(width 0.3)
		(layer "F.Cu")
		(net 7)
	)
	(segment
		(start 84.7 77.55)
		(end 85.492594 77.55)
		(width 0.3)
		(layer "F.Cu")
		(net 7)
	)
	(segment
		(start 85.492594 77.55)
		(end 86.392594 78.45)
		(width 0.3)
		(layer "F.Cu")
		(net 7)
	)
	(segment
		(start 100.45 92.75)
		(end 101.05 92.15)
		(width 0.3)
		(layer "F.Cu")
		(net 8)
	)
	(segment
		(start 100.98 92.08)
		(end 100.98 89.6)
		(width 0.3)
		(layer "F.Cu")
		(net 8)
	)
	(segment
		(start 101.05 92.15)
		(end 100.98 92.08)
		(width 0.3)
		(layer "F.Cu")
		(net 8)
	)
	(segment
		(start 98.501 92.75)
		(end 100.45 92.75)
		(width 0.3)
		(layer "F.Cu")
		(net 8)
	)
	(segment
		(start 100.73 91.846)
		(end 99.976 92.6)
		(width 0.2)
		(layer "F.Cu")
		(net 8)
	)
	(segment
		(start 99.976 92.6)
		(end 98.126 92.6)
		(width 0.2)
		(layer "F.Cu")
		(net 8)
	)
	(segment
		(start 87.08 82.545)
		(end 87.08 81.3)
		(width 0.2)
		(layer "B.Cu")
		(net 9)
	)
	(segment
		(start 86.547 82.649)
		(end 86.247001 82.649)
		(width 0.2)
		(layer "B.Cu")
		(net 9)
	)
	(segment
		(start 86.022 83.942)
		(end 86.33 84.25)
		(width 0.2)
		(layer "B.Cu")
		(net 9)
	)
	(segment
		(start 87.08 81.3)
		(end 87.4 80.98)
		(width 0.2)
		(layer "B.Cu")
		(net 9)
	)
	(segment
		(start 86.976 82.649)
		(end 87.08 82.545)
		(width 0.2)
		(layer "B.Cu")
		(net 9)
	)
	(segment
		(start 86.547 82.649)
		(end 86.976 82.649)
		(width 0.2)
		(layer "B.Cu")
		(net 9)
	)
	(segment
		(start 86.022 82.874001)
		(end 86.022 83.942)
		(width 0.2)
		(layer "B.Cu")
		(net 9)
	)
	(segment
		(start 86.247001 82.649)
		(end 86.022 82.874001)
		(width 0.2)
		(layer "B.Cu")
		(net 9)
	)
	(segment
		(start 99.52 80.577)
		(end 99.52 79.577)
		(width 0.2)
		(layer "F.Cu")
		(net 10)
	)
	(segment
		(start 98.35 81.747)
		(end 99.52 80.577)
		(width 0.2)
		(layer "F.Cu")
		(net 10)
	)
	(segment
		(start 97.625 83.45)
		(end 98.3 83.45)
		(width 0.2)
		(layer "F.Cu")
		(net 10)
	)
	(segment
		(start 99.243 79.3)
		(end 99.52 79.577)
		(width 0.2)
		(layer "F.Cu")
		(net 10)
	)
	(segment
		(start 98.35 83.4)
		(end 98.35 81.747)
		(width 0.2)
		(layer "F.Cu")
		(net 10)
	)
	(segment
		(start 96.8 79.82)
		(end 97.32 79.3)
		(width 0.2)
		(layer "F.Cu")
		(net 10)
	)
	(segment
		(start 98.3 83.45)
		(end 98.35 83.4)
		(width 0.2)
		(layer "F.Cu")
		(net 10)
	)
	(segment
		(start 97.32 79.3)
		(end 99.243 79.3)
		(width 0.2)
		(layer "F.Cu")
		(net 10)
	)
	(segment
		(start 95.22 87.98)
		(end 95.35 87.85)
		(width 0.25)
		(layer "F.Cu")
		(net 11)
	)
	(segment
		(start 95.22 88.4)
		(end 95.22 87.98)
		(width 0.25)
		(layer "F.Cu")
		(net 11)
	)
	(segment
		(start 95.35 87.85)
		(end 95.35 87.223)
		(width 0.25)
		(layer "F.Cu")
		(net 11)
	)
	(segment
		(start 97 81.5)
		(end 96.8 81.7)
		(width 0.25)
		(layer "F.Cu")
		(net 12)
	)
	(segment
		(start 97.2 81.5)
		(end 97 81.5)
		(width 0.25)
		(layer "F.Cu")
		(net 12)
	)
	(segment
		(start 95.8 79.82)
		(end 95.8 78.65)
		(width 0.2)
		(layer "F.Cu")
		(net 12)
	)
	(segment
		(start 96.8 81.7)
		(end 96.8 82.175)
		(width 0.25)
		(layer "F.Cu")
		(net 12)
	)
	(via
		(at 92.05 82.4)
		(size 0.45)
		(drill 0.2)
		(layers "F.Cu" "B.Cu")
		(net 12)
	)
	(via
		(at 95.8 78.65)
		(size 0.45)
		(drill 0.2)
		(layers "F.Cu" "B.Cu")
		(net 12)
	)
	(via
		(at 97.2 81.5)
		(size 0.45)
		(drill 0.2)
		(layers "F.Cu" "B.Cu")
		(net 12)
	)
	(segment
		(start 95.876 79.5)
		(end 92.9 79.5)
		(width 0.25)
		(layer "B.Cu")
		(net 12)
	)
	(segment
		(start 96.301 79.925)
		(end 95.876 79.5)
		(width 0.25)
		(layer "B.Cu")
		(net 12)
	)
	(segment
		(start 96.301 81.151)
		(end 96.301 79.925)
		(width 0.25)
		(layer "B.Cu")
		(net 12)
	)
	(segment
		(start 92.05 80.35)
		(end 92.05 82.4)
		(width 0.25)
		(layer "B.Cu")
		(net 12)
	)
	(segment
		(start 95.8 78.65)
		(end 95.8 79.424)
		(width 0.2)
		(layer "B.Cu")
		(net 12)
	)
	(segment
		(start 97.2 81.5)
		(end 96.65 81.5)
		(width 0.25)
		(layer "B.Cu")
		(net 12)
	)
	(segment
		(start 96.65 81.5)
		(end 96.301 81.151)
		(width 0.25)
		(layer "B.Cu")
		(net 12)
	)
	(segment
		(start 95.8 79.424)
		(end 95.876 79.5)
		(width 0.2)
		(layer "B.Cu")
		(net 12)
	)
	(segment
		(start 92.9 79.5)
		(end 92.05 80.35)
		(width 0.25)
		(layer "B.Cu")
		(net 12)
	)
	(segment
		(start 96.85 87.223)
		(end 96.85 87.85)
		(width 0.25)
		(layer "F.Cu")
		(net 13)
	)
	(segment
		(start 97.1 88.1)
		(end 97.1 88.52)
		(width 0.25)
		(layer "F.Cu")
		(net 13)
	)
	(segment
		(start 96.85 87.85)
		(end 97.1 88.1)
		(width 0.25)
		(layer "F.Cu")
		(net 13)
	)
	(segment
		(start 88.87 72.65)
		(end 88.92 72.7)
		(width 0.2)
		(layer "F.Cu")
		(net 14)
	)
	(segment
		(start 87.538 72.65)
		(end 88.87 72.65)
		(width 0.2)
		(layer "F.Cu")
		(net 14)
	)
	(segment
		(start 88.868 73.648)
		(end 88.92 73.7)
		(width 0.2)
		(layer "F.Cu")
		(net 15)
	)
	(segment
		(start 87.538 73.648)
		(end 88.868 73.648)
		(width 0.2)
		(layer "F.Cu")
		(net 15)
	)
	(segment
		(start 93.799 79.82)
		(end 94.899 79.82)
		(width 0.125)
		(layer "F.Cu")
		(net 16)
	)
	(segment
		(start 94.853 82.175)
		(end 94.853 80.833)
		(width 0.2)
		(layer "F.Cu")
		(net 17)
	)
	(segment
		(start 94.853 80.833)
		(end 94.8 80.78)
		(width 0.2)
		(layer "F.Cu")
		(net 17)
	)
	(segment
		(start 98.1 87.95)
		(end 97.625 87.475)
		(width 0.25)
		(layer "F.Cu")
		(net 18)
	)
	(segment
		(start 97.625 87.475)
		(end 97.625 86.449)
		(width 0.25)
		(layer "F.Cu")
		(net 18)
	)
	(segment
		(start 99.1 88.52)
		(end 98.1 88.52)
		(width 0.25)
		(layer "F.Cu")
		(net 18)
	)
	(segment
		(start 98.1 88.52)
		(end 98.1 87.95)
		(width 0.25)
		(layer "F.Cu")
		(net 18)
	)
	(segment
		(start 99.07 89.5)
		(end 99.92 89.5)
		(width 0.3)
		(layer "F.Cu")
		(net 19)
	)
	(segment
		(start 99.92 89.5)
		(end 100.02 89.6)
		(width 0.3)
		(layer "F.Cu")
		(net 19)
	)
	(segment
		(start 99.05 89.48)
		(end 99.07 89.5)
		(width 0.3)
		(layer "F.Cu")
		(net 19)
	)
	(segment
		(start 100.02 89.6)
		(end 100.02 88.6)
		(width 0.3)
		(layer "F.Cu")
		(net 19)
	)
	(segment
		(start 85.465 78.525)
		(end 84.725 78.525)
		(width 0.3)
		(layer "F.Cu")
		(net 20)
	)
	(segment
		(start 84.725 78.525)
		(end 84.65 78.45)
		(width 0.3)
		(layer "F.Cu")
		(net 20)
	)
	(segment
		(start 85.54 78.45)
		(end 85.465 78.525)
		(width 0.3)
		(layer "F.Cu")
		(net 20)
	)
	(segment
		(start 86.451 87.18)
		(end 86.548 87.277)
		(width 0.2)
		(layer "B.Cu")
		(net 22)
	)
	(segment
		(start 86.548 87.277)
		(end 86.548 88.403)
		(width 0.2)
		(layer "B.Cu")
		(net 22)
	)
	(segment
		(start 86.547 82.153)
		(end 86.547 81.077)
		(width 0.2)
		(layer "B.Cu")
		(net 24)
	)
	(segment
		(start 86.547 81.077)
		(end 86.45 80.98)
		(width 0.2)
		(layer "B.Cu")
		(net 24)
	)
	(segment
		(start 99.211211 71.87)
		(end 99.676 72.334789)
		(width 0.2)
		(layer "F.Cu")
		(net 25)
	)
	(segment
		(start 99.676 72.334789)
		(end 100.140789 71.87)
		(width 0.2)
		(layer "F.Cu")
		(net 25)
	)
	(segment
		(start 99.708302 72.334789)
		(end 99.676 72.334789)
		(width 0.2)
		(layer "F.Cu")
		(net 25)
	)
	(segment
		(start 100.140789 71.87)
		(end 101.05 71.87)
		(width 0.2)
		(layer "F.Cu")
		(net 25)
	)
	(segment
		(start 99.046136 71.87)
		(end 99.211211 71.87)
		(width 0.2)
		(layer "F.Cu")
		(net 25)
	)
	(via
		(at 82.276 89.85)
		(size 0.55)
		(drill 0.25)
		(layers "F.Cu" "B.Cu")
		(free yes)
		(net 25)
	)
	(via
		(at 82.276 90.45)
		(size 0.55)
		(drill 0.25)
		(layers "F.Cu" "B.Cu")
		(free yes)
		(net 25)
	)
	(via
		(at 89.6 89.9)
		(size 0.55)
		(drill 0.25)
		(layers "F.Cu" "B.Cu")
		(net 25)
	)
	(via
		(at 99.676 72.334789)
		(size 0.45)
		(drill 0.2)
		(layers "F.Cu" "B.Cu")
		(net 25)
	)
	(via
		(at 91.876 89.25)
		(size 0.55)
		(drill 0.25)
		(layers "F.Cu" "B.Cu")
		(free yes)
		(net 25)
	)
	(via
		(at 82.302 89.25)
		(size 0.55)
		(drill 0.25)
		(layers "F.Cu" "B.Cu")
		(free yes)
		(net 25)
	)
	(via
		(at 91.876 89.95)
		(size 0.55)
		(drill 0.25)
		(layers "F.Cu" "B.Cu")
		(free yes)
		(net 25)
	)
	(via
		(at 91.376 89.55)
		(size 0.55)
		(drill 0.25)
		(layers "F.Cu" "B.Cu")
		(free yes)
		(net 25)
	)
	(via
		(at 91.426 90.3)
		(size 0.55)
		(drill 0.25)
		(layers "F.Cu" "B.Cu")
		(free yes)
		(net 25)
	)
	(segment
		(start 100.75 86.078424)
		(end 100.75 87.949)
		(width 0.3)
		(layer "B.Cu")
		(net 25)
	)
	(segment
		(start 100.75 87.949)
		(end 99.1 89.599)
		(width 0.3)
		(layer "B.Cu")
		(net 25)
	)
	(segment
		(start 82.551 88.3)
		(end 82.551 86.65)
		(width 0.5)
		(layer "B.Cu")
		(net 25)
	)
	(segment
		(start 82.551 86.65)
		(end 82.901 86.3)
		(width 0.5)
		(layer "B.Cu")
		(net 25)
	)
	(segment
		(start 99.1 89.599)
		(end 97.95 89.599)
		(width 0.3)
		(layer "B.Cu")
		(net 25)
	)
	(segment
		(start 97.95 89.599)
		(end 96.469 89.599)
		(width 0.4)
		(layer "B.Cu")
		(net 25)
	)
	(segment
		(start 99.726 72.334789)
		(end 99.726 72.35)
		(width 0.3)
		(layer "B.Cu")
		(net 25)
	)
	(segment
		(start 88.146 90.1)
		(end 87.626 89.58)
		(width 0.2)
		(layer "B.Cu")
		(net 25)
	)
	(segment
		(start 88.906882 90.1)
		(end 88.146 90.1)
		(width 0.2)
		(layer "B.Cu")
		(net 25)
	)
	(segment
		(start 96.469 89.599)
		(end 96.4 89.53)
		(width 0.4)
		(layer "B.Cu")
		(net 25)
	)
	(segment
		(start 99.726 72.35)
		(end 100.4 73.024)
		(width 0.3)
		(layer "B.Cu")
		(net 25)
	)
	(segment
		(start 87.445 89.399)
		(end 87.626 89.58)
		(width 0.2)
		(layer "B.Cu")
		(net 25)
	)
	(segment
		(start 89.106882 89.9)
		(end 88.906882 90.1)
		(width 0.2)
		(layer "B.Cu")
		(net 25)
	)
	(segment
		(start 100.4 73.024)
		(end 100.4 85.728424)
		(width 0.3)
		(layer "B.Cu")
		(net 25)
	)
	(segment
		(start 89.6 89.9)
		(end 89.106882 89.9)
		(width 0.2)
		(layer "B.Cu")
		(net 25)
	)
	(segment
		(start 82.901 86.3)
		(end 83.151 86.3)
		(width 0.5)
		(layer "B.Cu")
		(net 25)
	)
	(segment
		(start 100.4 85.728424)
		(end 100.75 86.078424)
		(width 0.3)
		(layer "B.Cu")
		(net 25)
	)
	(segment
		(start 82.680836 88.170164)
		(end 82.551 88.3)
		(width 0.2)
		(layer "B.Cu")
		(net 25)
	)
	(segment
		(start 82.656 97.13)
		(end 83.5 97.13)
		(width 0.25)
		(layer "B.Cu")
		(net 26)
	)
	(segment
		(start 82.476 92.85)
		(end 82.076 93.25)
		(width 0.25)
		(layer "B.Cu")
		(net 26)
	)
	(segment
		(start 82.076 93.25)
		(end 82.076 96.55)
		(width 0.25)
		(layer "B.Cu")
		(net 26)
	)
	(segment
		(start 82.076 96.55)
		(end 82.656 97.13)
		(width 0.25)
		(layer "B.Cu")
		(net 26)
	)
	(segment
		(start 97.9 76.35)
		(end 98.35 75.9)
		(width 0.2)
		(layer "F.Cu")
		(net 27)
	)
	(segment
		(start 96.9 76.35)
		(end 97.9 76.35)
		(width 0.2)
		(layer "F.Cu")
		(net 27)
	)
	(segment
		(start 87.538 74.148)
		(end 88.298 74.148)
		(width 0.125)
		(layer "F.Cu")
		(net 27)
	)
	(segment
		(start 95.35 77.9)
		(end 96.9 76.35)
		(width 0.2)
		(layer "F.Cu")
		(net 27)
	)
	(segment
		(start 88.298 74.148)
		(end 88.35 74.2)
		(width 0.125)
		(layer "F.Cu")
		(net 27)
	)
	(segment
		(start 93.276 77.9)
		(end 95.35 77.9)
		(width 0.2)
		(layer "F.Cu")
		(net 27)
	)
	(segment
		(start 98.35 75.9)
		(end 98.35 75.25)
		(width 0.2)
		(layer "F.Cu")
		(net 27)
	)
	(via
		(at 88.35 74.2)
		(size 0.45)
		(drill 0.2)
		(layers "F.Cu" "B.Cu")
		(net 27)
	)
	(via
		(at 93.276 77.9)
		(size 0.45)
		(drill 0.2)
		(layers "F.Cu" "B.Cu")
		(net 27)
	)
	(segment
		(start 87.9 74.65)
		(end 88.35 74.2)
		(width 0.2)
		(layer "B.Cu")
		(net 27)
	)
	(segment
		(start 88.5 78.15)
		(end 87.9 77.55)
		(width 0.2)
		(layer "B.Cu")
		(net 27)
	)
	(segment
		(start 93.276 77.9)
		(end 92.25 77.9)
		(width 0.2)
		(layer "B.Cu")
		(net 27)
	)
	(segment
		(start 87.9 77.55)
		(end 87.9 74.65)
		(width 0.2)
		(layer "B.Cu")
		(net 27)
	)
	(segment
		(start 92.25 77.9)
		(end 92 78.15)
		(width 0.2)
		(layer "B.Cu")
		(net 27)
	)
	(segment
		(start 92 78.15)
		(end 88.5 78.15)
		(width 0.2)
		(layer "B.Cu")
		(net 27)
	)
	(segment
		(start 84.551 76.1)
		(end 84.852 75.799)
		(width 0.2)
		(layer "F.Cu")
		(net 28)
	)
	(segment
		(start 98.275 76.675)
		(end 99.7 75.25)
		(width 0.2)
		(layer "F.Cu")
		(net 28)
	)
	(segment
		(start 84.852 75.799)
		(end 84.852 75.337)
		(width 0.2)
		(layer "F.Cu")
		(net 28)
	)
	(segment
		(start 84.551 76.575)
		(end 84.551 76.1)
		(width 0.2)
		(layer "F.Cu")
		(net 28)
	)
	(segment
		(start 95.484619 78.225)
		(end 97.03462 76.675)
		(width 0.2)
		(layer "F.Cu")
		(net 28)
	)
	(segment
		(start 97.03462 76.675)
		(end 98.275 76.675)
		(width 0.2)
		(layer "F.Cu")
		(net 28)
	)
	(segment
		(start 94.811397 78.225)
		(end 95.484619 78.225)
		(width 0.2)
		(layer "F.Cu")
		(net 28)
	)
	(segment
		(start 94.011397 79.025)
		(end 94.811397 78.225)
		(width 0.2)
		(layer "F.Cu")
		(net 28)
	)
	(segment
		(start 84.8 75.655786)
		(end 84.852 75.603786)
		(width 0.125)
		(layer "F.Cu")
		(net 28)
	)
	(segment
		(start 93.176 79.025)
		(end 94.011397 79.025)
		(width 0.2)
		(layer "F.Cu")
		(net 28)
	)
	(segment
		(start 84.852 75.603786)
		(end 84.852 75.337)
		(width 0.125)
		(layer "F.Cu")
		(net 28)
	)
	(via
		(at 93.176 79.025)
		(size 0.45)
		(drill 0.2)
		(layers "F.Cu" "B.Cu")
		(net 28)
	)
	(via
		(at 84.551 76.575)
		(size 0.45)
		(drill 0.2)
		(layers "F.Cu" "B.Cu")
		(net 28)
	)
	(segment
		(start 84.551 76.575)
		(end 84.551 76.701)
		(width 0.2)
		(layer "B.Cu")
		(net 28)
	)
	(segment
		(start 93.151 79.05)
		(end 93.176 79.025)
		(width 0.2)
		(layer "B.Cu")
		(net 28)
	)
	(segment
		(start 84.551 76.701)
		(end 86.9 79.05)
		(width 0.2)
		(layer "B.Cu")
		(net 28)
	)
	(segment
		(start 86.9 79.05)
		(end 93.151 79.05)
		(width 0.2)
		(layer "B.Cu")
		(net 28)
	)
	(segment
		(start 86.85 70.9)
		(end 86.778152 70.828152)
		(width 0.2)
		(layer "F.Cu")
		(net 29)
	)
	(segment
		(start 86.35 70.828152)
		(end 86.35 71.462)
		(width 0.2)
		(layer "F.Cu")
		(net 29)
	)
	(segment
		(start 86.221848 70.828152)
		(end 86.35 70.828152)
		(width 0.2)
		(layer "F.Cu")
		(net 29)
	)
	(segment
		(start 85.2 69.55)
		(end 85.2 69.806303)
		(width 0.2)
		(layer "F.Cu")
		(net 29)
	)
	(segment
		(start 86.85 71.462)
		(end 86.85 70.9)
		(width 0.2)
		(layer "F.Cu")
		(net 29)
	)
	(segment
		(start 85.2 69.806303)
		(end 86.221848 70.828152)
		(width 0.2)
		(layer "F.Cu")
		(net 29)
	)
	(segment
		(start 86.778152 70.828152)
		(end 86.221848 70.828152)
		(width 0.2)
		(layer "F.Cu")
		(net 29)
	)
	(via
		(at 85.2 69.55)
		(size 0.55)
		(drill 0.25)
		(layers "F.Cu" "B.Cu")
		(net 29)
	)
	(segment
		(start 86.679 64.574)
		(end 86.679 65.321)
		(width 0.2)
		(layer "B.Cu")
		(net 29)
	)
	(segment
		(start 86.679 65.321)
		(end 86.4 65.6)
		(width 0.2)
		(layer "B.Cu")
		(net 29)
	)
	(segment
		(start 84.873 69.223)
		(end 85.2 69.55)
		(width 0.2)
		(layer "B.Cu")
		(net 29)
	)
	(segment
		(start 85 65.6)
		(end 84.873 65.727)
		(width 0.2)
		(layer "B.Cu")
		(net 29)
	)
	(segment
		(start 84.873 67.552)
		(end 84.873 69.223)
		(width 0.2)
		(layer "B.Cu")
		(net 29)
	)
	(segment
		(start 84.873 66.25)
		(end 84.873 67.552)
		(width 0.2)
		(layer "B.Cu")
		(net 29)
	)
	(segment
		(start 86.4 65.6)
		(end 85 65.6)
		(width 0.2)
		(layer "B.Cu")
		(net 29)
	)
	(segment
		(start 84.873 65.727)
		(end 84.873 66.25)
		(width 0.2)
		(layer "B.Cu")
		(net 29)
	)
	(segment
		(start 85.1125 70.6375)
		(end 85.3948 70.6375)
		(width 0.2)
		(layer "F.Cu")
		(net 33)
	)
	(segment
		(start 84.852 70.898)
		(end 85.1125 70.6375)
		(width 0.2)
		(layer "F.Cu")
		(net 33)
	)
	(segment
		(start 84.852 71.462)
		(end 84.852 70.898)
		(width 0.2)
		(layer "F.Cu")
		(net 33)
	)
	(segment
		(start 85.352 71.462)
		(end 85.352 70.6803)
		(width 0.2)
		(layer "F.Cu")
		(net 33)
	)
	(segment
		(start 85.352 70.6803)
		(end 85.3948 70.6375)
		(width 0.2)
		(layer "F.Cu")
		(net 33)
	)
	(via
		(at 85.3948 70.6375)
		(size 0.45)
		(drill 0.2)
		(layers "F.Cu" "B.Cu")
		(net 33)
	)
	(segment
		(start 89.678 64.574)
		(end 89.678 65.422)
		(width 0.2)
		(layer "B.Cu")
		(net 33)
	)
	(segment
		(start 85.3948 70.1552)
		(end 86.3 69.25)
		(width 0.2)
		(layer "B.Cu")
		(net 33)
	)
	(segment
		(start 86.3 69.25)
		(end 87.2 69.25)
		(width 0.2)
		(layer "B.Cu")
		(net 33)
	)
	(segment
		(start 88.2 65.6)
		(end 87.873 65.927)
		(width 0.2)
		(layer "B.Cu")
		(net 33)
	)
	(segment
		(start 87.2 69.25)
		(end 87.873 68.577)
		(width 0.2)
		(layer "B.Cu")
		(net 33)
	)
	(segment
		(start 89.678 65.422)
		(end 89.5 65.6)
		(width 0.2)
		(layer "B.Cu")
		(net 33)
	)
	(segment
		(start 87.873 65.927)
		(end 87.873 66.25)
		(width 0.2)
		(layer "B.Cu")
		(net 33)
	)
	(segment
		(start 85.3948 70.6375)
		(end 85.3948 70.1552)
		(width 0.2)
		(layer "B.Cu")
		(net 33)
	)
	(segment
		(start 87.873 68.577)
		(end 87.873 67.552)
		(width 0.2)
		(layer "B.Cu")
		(net 33)
	)
	(segment
		(start 89.5 65.6)
		(end 88.2 65.6)
		(width 0.2)
		(layer "B.Cu")
		(net 33)
	)
	(segment
		(start 87.873 66.25)
		(end 87.873 67.552)
		(width 0.2)
		(layer "B.Cu")
		(net 33)
	)
	(segment
		(start 87.406772 69.856772)
		(end 87.45 69.9)
		(width 0.125)
		(layer "F.Cu")
		(net 37)
	)
	(segment
		(start 87.402 65.55)
		(end 87.402 68.211)
		(width 0.2)
		(layer "F.Cu")
		(net 37)
	)
	(segment
		(start 87.398 68.987)
		(end 87.398 69.998)
		(width 0.2)
		(layer "F.Cu")
		(net 37)
	)
	(segment
		(start 87.398 69.998)
		(end 87.4 70)
		(width 0.2)
		(layer "F.Cu")
		(net 37)
	)
	(segment
		(start 82.299214 72.673032)
		(end 82.275 72.648818)
		(width 0.2)
		(layer "F.Cu")
		(net 37)
	)
	(segment
		(start 82.275 72.648818)
		(end 82.275 70.305)
		(width 0.2)
		(layer "F.Cu")
		(net 37)
	)
	(segment
		(start 82.322246 72.65)
		(end 82.299214 72.673032)
		(width 0.2)
		(layer "F.Cu")
		(net 37)
	)
	(segment
		(start 87.398 68.215)
		(end 87.398 68.987)
		(width 0.2)
		(layer "F.Cu")
		(net 37)
	)
	(segment
		(start 83.613 72.7)
		(end 83.663 72.65)
		(width 0.125)
		(layer "F.Cu")
		(net 37)
	)
	(segment
		(start 83.663 72.65)
		(end 82.322246 72.65)
		(width 0.2)
		(layer "F.Cu")
		(net 37)
	)
	(segment
		(start 82.275 70.305)
		(end 82.35 70.23)
		(width 0.2)
		(layer "F.Cu")
		(net 37)
	)
	(segment
		(start 87.402 68.211)
		(end 87.398 68.215)
		(width 0.2)
		(layer "F.Cu")
		(net 37)
	)
	(via
		(at 87.4 70)
		(size 0.55)
		(drill 0.25)
		(layers "F.Cu" "B.Cu")
		(net 37)
	)
	(via
		(at 82.299214 72.673032)
		(size 0.55)
		(drill 0.25)
		(layers "F.Cu" "B.Cu")
		(net 37)
	)
	(segment
		(start 85.776968 72.673032)
		(end 87.4 71.05)
		(width 0.2)
		(layer "B.Cu")
		(net 37)
	)
	(segment
		(start 87.4 71.05)
		(end 87.4 70)
		(width 0.2)
		(layer "B.Cu")
		(net 37)
	)
	(segment
		(start 82.299214 72.673032)
		(end 85.776968 72.673032)
		(width 0.2)
		(layer "B.Cu")
		(net 37)
	)
	(segment
		(start 86.4 68.987)
		(end 86.4 70)
		(width 0.2)
		(layer "F.Cu")
		(net 38)
	)
	(segment
		(start 82.8 71.9582)
		(end 82.8 71.25)
		(width 0.2)
		(layer "F.Cu")
		(net 38)
	)
	(segment
		(start 83.35 70.23)
		(end 83.35 70.7)
		(width 0.2)
		(layer "F.Cu")
		(net 38)
	)
	(segment
		(start 83.613 72.1)
		(end 83.663 72.15)
		(width 0.125)
		(layer "F.Cu")
		(net 38)
	)
	(segment
		(start 86.4 68.987)
		(end 86.4 68.215)
		(width 0.2)
		(layer "F.Cu")
		(net 38)
	)
	(segment
		(start 82.8 72.15)
		(end 82.8 71.9582)
		(width 0.125)
		(layer "F.Cu")
		(net 38)
	)
	(segment
		(start 82.8 71.9582)
		(end 82.8 71.999338)
		(width 0.125)
		(layer "F.Cu")
		(net 38)
	)
	(segment
		(start 82.9918 72.15)
		(end 82.8 71.9582)
		(width 0.2)
		(layer "F.Cu")
		(net 38)
	)
	(segment
		(start 82.8 71.25)
		(end 83.35 70.7)
		(width 0.2)
		(layer "F.Cu")
		(net 38)
	)
	(segment
		(start 86.401 68.214)
		(end 86.4 68.215)
		(width 0.2)
		(layer "F.Cu")
		(net 38)
	)
	(segment
		(start 83.663 72.15)
		(end 82.9918 72.15)
		(width 0.2)
		(layer "F.Cu")
		(net 38)
	)
	(segment
		(start 86.401 65.55)
		(end 86.401 68.214)
		(width 0.2)
		(layer "F.Cu")
		(net 38)
	)
	(via
		(at 82.8 71.9582)
		(size 0.55)
		(drill 0.25)
		(layers "F.Cu" "B.Cu")
		(net 38)
	)
	(via
		(at 86.4 70)
		(size 0.55)
		(drill 0.25)
		(layers "F.Cu" "B.Cu")
		(net 38)
	)
	(segment
		(start 86.4 70.75)
		(end 85.1918 71.9582)
		(width 0.2)
		(layer "B.Cu")
		(net 38)
	)
	(segment
		(start 85.1918 71.9582)
		(end 82.8 71.9582)
		(width 0.2)
		(layer "B.Cu")
		(net 38)
	)
	(segment
		(start 86.4 70)
		(end 86.4 70.75)
		(width 0.2)
		(layer "B.Cu")
		(net 38)
	)
	(segment
		(start 88.575 83.38)
		(end 87.58 83.38)
		(width 0.125)
		(layer "B.Cu")
		(net 39)
	)
	(segment
		(start 87.349 83.149)
		(end 86.547 83.149)
		(width 0.125)
		(layer "B.Cu")
		(net 39)
	)
	(segment
		(start 87.58 83.38)
		(end 87.349 83.149)
		(width 0.125)
		(layer "B.Cu")
		(net 39)
	)
	(segment
		(start 86.847 89.399)
		(end 87.626 88.62)
		(width 0.2)
		(layer "B.Cu")
		(net 40)
	)
	(segment
		(start 87.646 88.62)
		(end 88.576 89.55)
		(width 0.2)
		(layer "B.Cu")
		(net 40)
	)
	(segment
		(start 88.576 89.55)
		(end 88.576 89.58)
		(width 0.2)
		(layer "B.Cu")
		(net 40)
	)
	(segment
		(start 87.626 88.62)
		(end 87.646 88.62)
		(width 0.2)
		(layer "B.Cu")
		(net 40)
	)
	(segment
		(start 86.548 89.399)
		(end 86.847 89.399)
		(width 0.2)
		(layer "B.Cu")
		(net 40)
	)
	(segment
		(start 82.0516 73.6984)
		(end 82.0516 78.3516)
		(width 0.2)
		(layer "F.Cu")
		(net 41)
	)
	(segment
		(start 82.6 73.15)
		(end 82.0516 73.6984)
		(width 0.2)
		(layer "F.Cu")
		(net 41)
	)
	(segment
		(start 83.663 73.15)
		(end 82.6 73.15)
		(width 0.2)
		(layer "F.Cu")
		(net 41)
	)
	(segment
		(start 82.0516 78.3516)
		(end 82.45 78.75)
		(width 0.2)
		(layer "F.Cu")
		(net 41)
	)
	(segment
		(start 83.9 73.15)
		(end 82.6 73.15)
		(width 0.125)
		(layer "F.Cu")
		(net 41)
	)
	(segment
		(start 83.3628 71.4248)
		(end 83.4 71.462)
		(width 0.125)
		(layer "F.Cu")
		(net 42)
	)
	(segment
		(start 82.676 75.35)
		(end 82.6008 75.4252)
		(width 0.25)
		(layer "F.Cu")
		(net 42)
	)
	(segment
		(start 84.351 71.462)
		(end 84.351 70.231)
		(width 0.2)
		(layer "F.Cu")
		(net 42)
	)
	(segment
		(start 84.351 70.231)
		(end 84.35 70.23)
		(width 0.2)
		(layer "F.Cu")
		(net 42)
	)
	(segment
		(start 82.6008 75.4252)
		(end 82.6008 75.438)
		(width 0.25)
		(layer "F.Cu")
		(net 42)
	)
	(segment
		(start 83.4 71.462)
		(end 84.351 71.462)
		(width 0.125)
		(layer "F.Cu")
		(net 42)
	)
	(via
		(at 83.3628 71.4248)
		(size 0.45)
		(drill 0.2)
		(layers "F.Cu" "B.Cu")
		(net 42)
	)
	(via
		(at 82.676 75.35)
		(size 0.45)
		(drill 0.2)
		(layers "F.Cu" "B.Cu")
		(net 42)
	)
	(segment
		(start 82.676 75.35)
		(end 82.462 75.35)
		(width 0.125)
		(layer "In2.Cu")
		(net 42)
	)
	(segment
		(start 82.016 74.904)
		(end 82.016 73.645676)
		(width 0.125)
		(layer "In2.Cu")
		(net 42)
	)
	(segment
		(start 82.016 73.645676)
		(end 83.2875 72.374176)
		(width 0.125)
		(layer "In2.Cu")
		(net 42)
	)
	(segment
		(start 83.2875 71.5001)
		(end 83.3628 71.4248)
		(width 0.125)
		(layer "In2.Cu")
		(net 42)
	)
	(segment
		(start 83.2875 72.374176)
		(end 83.2875 71.5001)
		(width 0.125)
		(layer "In2.Cu")
		(net 42)
	)
	(segment
		(start 82.462 75.35)
		(end 82.016 74.904)
		(width 0.125)
		(layer "In2.Cu")
		(net 42)
	)
	(segment
		(start 97.95 82.95)
		(end 98.025 82.875)
		(width 0.2)
		(layer "F.Cu")
		(net 43)
	)
	(segment
		(start 98.025 81.425)
		(end 97.8 81.2)
		(width 0.2)
		(layer "F.Cu")
		(net 43)
	)
	(segment
		(start 97.8 81.2)
		(end 97.8 80.78)
		(width 0.2)
		(layer "F.Cu")
		(net 43)
	)
	(segment
		(start 97.625 82.95)
		(end 97.95 82.95)
		(width 0.2)
		(layer "F.Cu")
		(net 43)
	)
	(segment
		(start 98.025 82.875)
		(end 98.025 81.425)
		(width 0.2)
		(layer "F.Cu")
		(net 43)
	)
	(segment
		(start 99.52 81.577)
		(end 99.52 81.537)
		(width 0.125)
		(layer "F.Cu")
		(net 44)
	)
	(segment
		(start 97.625 83.95)
		(end 98.5 83.95)
		(width 0.2)
		(layer "F.Cu")
		(net 44)
	)
	(segment
		(start 98.5 83.95)
		(end 98.675 83.775)
		(width 0.2)
		(layer "F.Cu")
		(net 44)
	)
	(segment
		(start 98.675 83.775)
		(end 98.675 82.422)
		(width 0.2)
		(layer "F.Cu")
		(net 44)
	)
	(segment
		(start 98.675 82.422)
		(end 99.52 81.577)
		(width 0.2)
		(layer "F.Cu")
		(net 44)
	)
	(segment
		(start 100.48 80.577)
		(end 100.48 80.617)
		(width 0.2)
		(layer "F.Cu")
		(net 44)
	)
	(segment
		(start 100.48 80.617)
		(end 99.52 81.577)
		(width 0.2)
		(layer "F.Cu")
		(net 44)
	)
	(segment
		(start 95.503 82.175)
		(end 95.503 81.077)
		(width 0.2)
		(layer "F.Cu")
		(net 45)
	)
	(segment
		(start 95.503 81.077)
		(end 95.8 80.78)
		(width 0.2)
		(layer "F.Cu")
		(net 45)
	)
	(segment
		(start 98.55 84.45)
		(end 97.625 84.45)
		(width 0.2)
		(layer "F.Cu")
		(net 46)
	)
	(segment
		(start 99 82.75)
		(end 99 84)
		(width 0.2)
		(layer "F.Cu")
		(net 46)
	)
	(segment
		(start 99.52 82.577)
		(end 99.173 82.577)
		(width 0.2)
		(layer "F.Cu")
		(net 46)
	)
	(segment
		(start 99.173 82.577)
		(end 99 82.75)
		(width 0.2)
		(layer "F.Cu")
		(net 46)
	)
	(segment
		(start 99 84)
		(end 98.55 84.45)
		(width 0.2)
		(layer "F.Cu")
		(net 46)
	)
	(segment
		(start 88.351 87.18)
		(end 87.401 87.18)
		(width 0.2)
		(layer "B.Cu")
		(net 47)
	)
	(segment
		(start 86.847999 88.899)
		(end 87.076 88.670999)
		(width 0.2)
		(layer "B.Cu")
		(net 47)
	)
	(segment
		(start 86.548 88.899)
		(end 86.847999 88.899)
		(width 0.2)
		(layer "B.Cu")
		(net 47)
	)
	(segment
		(start 87.076 87.505)
		(end 87.401 87.18)
		(width 0.2)
		(layer "B.Cu")
		(net 47)
	)
	(segment
		(start 87.076 88.670999)
		(end 87.076 87.505)
		(width 0.2)
		(layer "B.Cu")
		(net 47)
	)
	(segment
		(start 96.151 81.429)
		(end 96.8 80.78)
		(width 0.2)
		(layer "F.Cu")
		(net 48)
	)
	(segment
		(start 96.151 82.175)
		(end 96.151 81.429)
		(width 0.2)
		(layer "F.Cu")
		(net 48)
	)
	(segment
		(start 93.851 82.175)
		(end 93.851 80.832)
		(width 0.2)
		(layer "F.Cu")
		(net 49)
	)
	(segment
		(start 93.351 82.175)
		(end 93.351 81.228)
		(width 0.2)
		(layer "F.Cu")
		(net 49)
	)
	(segment
		(start 93.351 81.228)
		(end 93.799 80.78)
		(width 0.2)
		(layer "F.Cu")
		(net 49)
	)
	(segment
		(start 93.851 80.832)
		(end 93.799 80.78)
		(width 0.2)
		(layer "F.Cu")
		(net 49)
	)
	(segment
		(start 98.951 86.6)
		(end 99.77 86.6)
		(width 0.2)
		(layer "F.Cu")
		(net 50)
	)
	(segment
		(start 98.3 85.949)
		(end 98.951 86.6)
		(width 0.2)
		(layer "F.Cu")
		(net 50)
	)
	(segment
		(start 97.625 85.949)
		(end 98.3 85.949)
		(width 0.2)
		(layer "F.Cu")
		(net 50)
	)
	(segment
		(start 97.625 85.447)
		(end 98.316603 85.447)
		(width 0.2)
		(layer "F.Cu")
		(net 51)
	)
	(segment
		(start 99.52 84.577)
		(end 99.52 83.577)
		(width 0.2)
		(layer "F.Cu")
		(net 51)
	)
	(segment
		(start 99.186603 84.577)
		(end 99.52 84.577)
		(width 0.2)
		(layer "F.Cu")
		(net 51)
	)
	(segment
		(start 98.316603 85.447)
		(end 99.186603 84.577)
		(width 0.2)
		(layer "F.Cu")
		(net 51)
	)
	(segment
		(start 92.706 80.78)
		(end 92.776 80.78)
		(width 0.2)
		(layer "F.Cu")
		(net 52)
	)
	(segment
		(start 87.232171 75.9)
		(end 87.278691 75.94652)
		(width 0.2)
		(layer "F.Cu")
		(net 52)
	)
	(segment
		(start 91.987584 78.60043)
		(end 91.987584 80.061584)
		(width 0.2)
		(layer "F.Cu")
		(net 52)
	)
	(segment
		(start 86.85 75.337)
		(end 86.85 75.7)
		(width 0.2)
		(layer "F.Cu")
		(net 52)
	)
	(segment
		(start 91.987584 80.061584)
		(end 92.706 80.78)
		(width 0.2)
		(layer "F.Cu")
		(net 52)
	)
	(segment
		(start 86.85 75.7)
		(end 86.95 75.8)
		(width 0.2)
		(layer "F.Cu")
		(net 52)
	)
	(segment
		(start 86.95 75.8)
		(end 87.05 75.9)
		(width 0.2)
		(layer "F.Cu")
		(net 52)
	)
	(segment
		(start 87.05 75.9)
		(end 87.232171 75.9)
		(width 0.2)
		(layer "F.Cu")
		(net 52)
	)
	(via
		(at 91.987584 78.60043)
		(size 0.45)
		(drill 0.2)
		(layers "F.Cu" "B.Cu")
		(net 52)
	)
	(via
		(at 87.278691 75.94652)
		(size 0.45)
		(drill 0.2)
		(layers "F.Cu" "B.Cu")
		(net 52)
	)
	(segment
		(start 87.278691 78.028691)
		(end 87.278691 75.94652)
		(width 0.2)
		(layer "B.Cu")
		(net 52)
	)
	(segment
		(start 87.75 78.5)
		(end 87.278691 78.028691)
		(width 0.2)
		(layer "B.Cu")
		(net 52)
	)
	(segment
		(start 91.987584 78.60043)
		(end 91.887154 78.5)
		(width 0.2)
		(layer "B.Cu")
		(net 52)
	)
	(segment
		(start 91.887154 78.5)
		(end 87.75 78.5)
		(width 0.2)
		(layer "B.Cu")
		(net 52)
	)
	(segment
		(start 85.976 75.463)
		(end 85.85 75.337)
		(width 0.2)
		(layer "F.Cu")
		(net 53)
	)
	(segment
		(start 83.69 77.436)
		(end 84.101 77.025)
		(width 0.2)
		(layer "F.Cu")
		(net 53)
	)
	(segment
		(start 84.101 77.025)
		(end 85.599529 77.025)
		(width 0.2)
		(layer "F.Cu")
		(net 53)
	)
	(segment
		(start 83.69 77.5)
		(end 83.69 77.436)
		(width 0.2)
		(layer "F.Cu")
		(net 53)
	)
	(segment
		(start 85.599529 77.025)
		(end 85.976 76.648529)
		(width 0.2)
		(layer "F.Cu")
		(net 53)
	)
	(segment
		(start 85.976 76.648529)
		(end 85.976 75.463)
		(width 0.2)
		(layer "F.Cu")
		(net 53)
	)
	(segment
		(start 87.538 74.649)
		(end 88.125 74.649)
		(width 0.25)
		(layer "F.Cu")
		(net 54)
	)
	(segment
		(start 88.125 74.649)
		(end 88.601 75.125)
		(width 0.25)
		(layer "F.Cu")
		(net 54)
	)
	(segment
		(start 83.898 74.15)
		(end 83.9 74.148)
		(width 0.125)
		(layer "F.Cu")
		(net 55)
	)
	(segment
		(start 82.666 74.38)
		(end 82.898 74.148)
		(width 0.3)
		(layer "F.Cu")
		(net 55)
	)
	(segment
		(start 82.898 74.148)
		(end 83.663 74.148)
		(width 0.3)
		(layer "F.Cu")
		(net 55)
	)
	(segment
		(start 82.616 74.38)
		(end 82.666 74.38)
		(width 0.3)
		(layer "F.Cu")
		(net 55)
	)
	(segment
		(start 86.35 76.124)
		(end 86.35 75.337)
		(width 0.25)
		(layer "F.Cu")
		(net 56)
	)
	(segment
		(start 86.6292 76.4032)
		(end 86.35 76.124)
		(width 0.25)
		(layer "F.Cu")
		(net 56)
	)
	(segment
		(start 86.7664 76.4032)
		(end 86.6292 76.4032)
		(width 0.25)
		(layer "F.Cu")
		(net 56)
	)
	(segment
		(start 85.352 75.337)
		(end 85.352 76.152)
		(width 0.15)
		(layer "F.Cu")
		(net 57)
	)
	(segment
		(start 85.352 76.152)
		(end 85.4 76.2)
		(width 0.15)
		(layer "F.Cu")
		(net 57)
	)
	(segment
		(start 85.401 76.45)
		(end 85.401 76.201)
		(width 0.125)
		(layer "F.Cu")
		(net 57)
	)
	(segment
		(start 85.401 76.201)
		(end 85.4 76.2)
		(width 0.125)
		(layer "F.Cu")
		(net 57)
	)
	(segment
		(start 87.898 68.215)
		(end 87.898 68.052)
		(width 0.25)
		(layer "F.Cu")
		(net 61)
	)
	(segment
		(start 87.898 68.987)
		(end 87.898 68.215)
		(width 0.25)
		(layer "F.Cu")
		(net 61)
	)
	(segment
		(start 88.92 68.2)
		(end 88.92 67.6)
		(width 0.2)
		(layer "F.Cu")
		(net 61)
	)
	(segment
		(start 88.92 67.6)
		(end 88.52 67.2)
		(width 0.2)
		(layer "F.Cu")
		(net 61)
	)
	(segment
		(start 88.52 67.02)
		(end 88.4 66.9)
		(width 0.25)
		(layer "F.Cu")
		(net 61)
	)
	(segment
		(start 88.298 65.652)
		(end 88.4 65.55)
		(width 0.125)
		(layer "F.Cu")
		(net 61)
	)
	(segment
		(start 87.898 67.752)
		(end 88.45 67.2)
		(width 0.2)
		(layer "F.Cu")
		(net 61)
	)
	(segment
		(start 88.52 67.2)
		(end 88.52 67.02)
		(width 0.25)
		(layer "F.Cu")
		(net 61)
	)
	(segment
		(start 88.4 66.9)
		(end 88.4 65.55)
		(width 0.25)
		(layer "F.Cu")
		(net 61)
	)
	(segment
		(start 87.898 68.987)
		(end 87.898 68.352)
		(width 0.2)
		(layer "F.Cu")
		(net 61)
	)
	(segment
		(start 87.898 68.215)
		(end 87.898 67.752)
		(width 0.2)
		(layer "F.Cu")
		(net 61)
	)
	(segment
		(start 88.45 67.2)
		(end 88.52 67.2)
		(width 0.2)
		(layer "F.Cu")
		(net 61)
	)
	(segment
		(start 92.951 72.875)
		(end 92.276 73.55)
		(width 0.2)
		(layer "F.Cu")
		(net 63)
	)
	(segment
		(start 92.473823 79.047823)
		(end 92.473823 73.767823)
		(width 0.2)
		(layer "F.Cu")
		(net 63)
	)
	(segment
		(start 92.951 72.099)
		(end 94.225 72.099)
		(width 0.3)
		(layer "F.Cu")
		(net 63)
	)
	(segment
		(start 92.951 72.099)
		(end 92.951 72.875)
		(width 0.2)
		(layer "F.Cu")
		(net 63)
	)
	(segment
		(start 93.022 72.17)
		(end 92.951 72.099)
		(width 0.2)
		(layer "F.Cu")
		(net 63)
	)
	(segment
		(start 92.776 79.35)
		(end 92.473823 79.047823)
		(width 0.2)
		(layer "F.Cu")
		(net 63)
	)
	(segment
		(start 92.473823 73.767823)
		(end 92.256 73.55)
		(width 0.2)
		(layer "F.Cu")
		(net 63)
	)
	(segment
		(start 94.225 72.099)
		(end 94.376 72.25)
		(width 0.2)
		(layer "F.Cu")
		(net 63)
	)
	(segment
		(start 92.276 73.55)
		(end 92.256 73.55)
		(width 0.2)
		(layer "F.Cu")
		(net 63)
	)
	(segment
		(start 92.776 79.82)
		(end 92.776 79.35)
		(width 0.2)
		(layer "F.Cu")
		(net 63)
	)
	(segment
		(start 97.826 73)
		(end 97.826 72.83)
		(width 0.3)
		(layer "F.Cu")
		(net 64)
	)
	(segment
		(start 97 73.826)
		(end 97.826 73)
		(width 0.3)
		(layer "F.Cu")
		(net 64)
	)
	(segment
		(start 97 73.85)
		(end 97 73.826)
		(width 0.3)
		(layer "F.Cu")
		(net 64)
	)
	(segment
		(start 91.876 106.555)
		(end 91.851 106.53)
		(width 0.3)
		(layer "F.Cu")
		(net 65)
	)
	(segment
		(start 91.876 107.8)
		(end 91.876 106.555)
		(width 0.3)
		(layer "F.Cu")
		(net 65)
	)
	(segment
		(start 98.35 73.756)
		(end 98.37 73.756)
		(width 0.2)
		(layer "F.Cu")
		(net 66)
	)
	(segment
		(start 99.276 72.85)
		(end 99.276 72.83)
		(width 0.2)
		(layer "F.Cu")
		(net 66)
	)
	(segment
		(start 98.37 73.756)
		(end 99.276 72.85)
		(width 0.2)
		(layer "F.Cu")
		(net 66)
	)
	(segment
		(start 98.35 73.85)
		(end 98.35 73.756)
		(width 0.125)
		(layer "F.Cu")
		(net 66)
	)
	(segment
		(start 99.7 73.85)
		(end 99.776 73.85)
		(width 0.2)
		(layer "F.Cu")
		(net 67)
	)
	(segment
		(start 99.776 73.85)
		(end 100.376 73.25)
		(width 0.2)
		(layer "F.Cu")
		(net 67)
	)
	(segment
		(start 100.376 73.25)
		(end 100.376 72.83)
		(width 0.2)
		(layer "F.Cu")
		(net 67)
	)
	(segment
		(start 101.176 73.03)
		(end 101.176 73.724)
		(width 0.2)
		(layer "F.Cu")
		(net 68)
	)
	(segment
		(start 101.376 72.83)
		(end 101.176 73.03)
		(width 0.2)
		(layer "F.Cu")
		(net 68)
	)
	(segment
		(start 101.176 73.724)
		(end 101.05 73.85)
		(width 0.2)
		(layer "F.Cu")
		(net 68)
	)
	(segment
		(start 102.576 72.83)
		(end 102.526 72.88)
		(width 0.2)
		(layer "F.Cu")
		(net 69)
	)
	(segment
		(start 102.526 72.88)
		(end 102.526 73.724)
		(width 0.2)
		(layer "F.Cu")
		(net 69)
	)
	(segment
		(start 102.526 73.724)
		(end 102.4 73.85)
		(width 0.2)
		(layer "F.Cu")
		(net 69)
	)
	(zone
		(net 12)
		(net_name "Net-(U2-V_{CIN})")
		(layer "F.Cu")
		(hatch edge 0.5)
		(priority 3)
		(connect_pads yes
			(clearance 0.3)
		)
		(min_thickness 0.25)
		(filled_areas_thickness no)
		(fill yes
			(thermal_gap 0.5)
			(thermal_bridge_width 0.5)
		)
		(polygon
			(pts
				(xy 92.8 84.3) (xy 87.076 84.3) (xy 86.3 85.05) (xy 84.35 85.05) (xy 84.35 82.475) (xy 90.925 82.475)
				(xy 91.05 82.35) (xy 91.05 81.9) (xy 92.25 81.9) (xy 92.8 82.85) (xy 92.8 84.15)
			)
		)
	)
	(zone
		(net 12)
		(net_name "Net-(U2-V_{CIN})")
		(layer "F.Cu")
		(hatch edge 0.5)
		(priority 8)
		(connect_pads yes
			(clearance 0.25)
		)
		(min_thickness 0.25)
		(filled_areas_thickness no)
		(fill yes
			(thermal_gap 0.5)
			(thermal_bridge_width 0.5)
		)
		(polygon
			(pts
				(xy 81.85 85.05) (xy 86.3 85.05) (xy 86.326 87.35) (xy 90.076 91.15) (xy 90.126 93.2) (xy 81.876 93.2)
			)
		)
	)
	(zone
		(net 2)
		(net_name "GND")
		(layer "F.Cu")
		(hatch edge 0.5)
		(priority 24)
		(connect_pads yes
			(clearance 0.25)
		)
		(min_thickness 0.25)
		(filled_areas_thickness no)
		(fill yes
			(thermal_gap 0.5)
			(thermal_bridge_width 0.5)
		)
		(polygon
			(pts
				(xy 82.326 97.7) (xy 93.576 97.7) (xy 93.576 100.35) (xy 86.326 100.35) (xy 85.576 101.1) (xy 85.576 103.35)
				(xy 82.326 103.35)
			)
		)
	)
	(zone
		(net 6)
		(net_name "VBUS")
		(layer "F.Cu")
		(hatch edge 0.5)
		(priority 1)
		(connect_pads yes
			(clearance 0.25)
		)
		(min_thickness 0.25)
		(filled_areas_thickness no)
		(fill yes
			(thermal_gap 0.5)
			(thermal_bridge_width 0.5)
		)
		(polygon
			(pts
				(xy 88.1 75.6) (xy 88.1 78) (xy 92.1 78) (xy 92.1 70.55) (xy 90.276 70.55) (xy 90.276 74.2) (xy 90.225 74.2)
				(xy 89.7 74.65) (xy 89.475 74.825) (xy 88.7 74.8) (xy 88.7 75.6)
			)
		)
	)
	(zone
		(net 8)
		(net_name "Net-(L1-Pad1)")
		(layer "F.Cu")
		(hatch edge 0.5)
		(priority 8)
		(connect_pads yes
			(clearance 0.25)
		)
		(min_thickness 0.25)
		(filled_areas_thickness no)
		(fill yes
			(thermal_gap 0.5)
			(thermal_bridge_width 0.5)
		)
		(polygon
			(pts
				(xy 92.676 86.55) (xy 94.6 86.55) (xy 94.6 88.75) (xy 98.576 91.55) (xy 102.376 91.45) (xy 102.376 94.05)
				(xy 94.276 94.05) (xy 94.301 91.275) (xy 92.676 90.05)
			)
		)
	)
	(zone
		(net 25)
		(net_name "+5V")
		(layer "F.Cu")
		(hatch edge 0.5)
		(priority 28)
		(connect_pads yes
			(clearance 0.25)
		)
		(min_thickness 0.25)
		(filled_areas_thickness no)
		(fill yes
			(thermal_gap 0.5)
			(thermal_bridge_width 0.5)
		)
		(polygon
			(pts
				(xy 90.176 89.05) (xy 92.376 89.05) (xy 92.376 90.65) (xy 90.176 90.65)
			)
		)
	)
	(zone
		(net 3)
		(net_name "VCC")
		(layer "F.Cu")
		(hatch edge 0.5)
		(priority 2)
		(connect_pads yes
			(clearance 0.5)
		)
		(min_thickness 0.25)
		(filled_areas_thickness no)
		(fill yes
			(thermal_gap 0.5)
			(thermal_bridge_width 0.5)
		)
		(polygon
			(pts
				(xy 90 78.6) (xy 90 82) (xy 88.3 82) (xy 88.3 82.3) (xy 81.75 82.3) (xy 81.75 79.1) (xy 87.2 79.1)
				(xy 87.2 78.6)
			)
		)
	)
	(zone
		(net 2)
		(net_name "GND")
		(layer "F.Cu")
		(hatch edge 0.5)
		(priority 27)
		(connect_pads
			(clearance 0.25)
		)
		(min_thickness 0.25)
		(filled_areas_thickness no)
		(fill yes
			(thermal_gap 0.5)
			(thermal_bridge_width 0.5)
		)
		(polygon
			(pts
				(xy 91.001 108.725) (xy 92.751 108.725) (xy 92.751 110.175) (xy 91.001 110.175)
			)
		)
	)
	(zone
		(net 2)
		(net_name "GND")
		(layer "F.Cu")
		(hatch edge 0.5)
		(priority 10)
		(connect_pads yes
			(clearance 0.3)
		)
		(min_thickness 0.25)
		(filled_areas_thickness no)
		(fill yes
			(thermal_gap 0.5)
			(thermal_bridge_width 0.5)
		)
		(polygon
			(pts
				(xy 95.253 84.1) (xy 95.253 85.869) (xy 95.75 86.4) (xy 96.85 86.4) (xy 96.85 83) (xy 95.75 83)
				(xy 95.75 83.85)
			)
		)
	)
	(zone
		(net 2)
		(net_name "GND")
		(layer "F.Cu")
		(hatch edge 0.5)
		(connect_pads yes
			(clearance 0.25)
		)
		(min_thickness 0.25)
		(filled_areas_thickness no)
		(fill yes
			(thermal_gap 0.5)
			(thermal_bridge_width 0.5)
		)
		(polygon
			(pts
				(xy 97.326 71.4) (xy 97.326 73.1) (xy 95.576 73.1) (xy 95.576 71.4) (xy 96.476 71.4)
			)
		)
	)
	(zone
		(net 5)
		(net_name "+12V")
		(layer "F.Cu")
		(hatch edge 0.5)
		(priority 29)
		(connect_pads yes
			(clearance 0.25)
		)
		(min_thickness 0.25)
		(filled_areas_thickness no)
		(fill yes
			(thermal_gap 0.5)
			(thermal_bridge_width 0.5)
		)
		(polygon
			(pts
				(xy 89.176 104.35) (xy 92.476 104.35) (xy 92.476 105.85) (xy 89.176 105.85)
			)
		)
	)
	(zone
		(net 5)
		(net_name "+12V")
		(layer "F.Cu")
		(hatch edge 0.5)
		(priority 26)
		(connect_pads yes
			(clearance 0.25)
		)
		(min_thickness 0.25)
		(filled_areas_thickness no)
		(fill yes
			(thermal_gap 0.5)
			(thermal_bridge_width 0.5)
		)
		(polygon
			(pts
				(xy 94.001 95.1) (xy 102.501 95.1) (xy 102.501 99.4) (xy 94.001 99.4)
			)
		)
	)
	(zone
		(net 2)
		(net_name "GND")
		(layer "F.Cu")
		(hatch edge 0.5)
		(priority 9)
		(connect_pads yes
			(clearance 0.3)
		)
		(min_thickness 0.25)
		(filled_areas_thickness no)
		(fill yes
			(thermal_gap 0.5)
			(thermal_bridge_width 0.5)
		)
		(polygon
			(pts
				(xy 86.576 86.65) (xy 86.576 85.25) (xy 87.176 84.65) (xy 87.876 84.65) (xy 91.8 84.7) (xy 92.85 84.7)
				(xy 92.85 86.45) (xy 92.176 87.4) (xy 87.376 87.45)
			)
		)
	)
	(zone
		(net 6)
		(net_name "VBUS")
		(layers "F.Cu" "B.Cu" "In2.Cu")
		(hatch edge 0.5)
		(priority 15)
		(connect_pads yes
			(clearance 0.125)
		)
		(min_thickness 0.25)
		(filled_areas_thickness no)
		(fill yes
			(thermal_gap 0.5)
			(thermal_bridge_width 0.5)
		)
		(polygon
			(pts
				(xy 88.1 78) (xy 92.3 78) (xy 92.3 68.2) (xy 89.5 68.2) (xy 89.5 70.1) (xy 88.1 70.1)
			)
		)
	)
	(zone
		(net 5)
		(net_name "+12V")
		(layer "B.Cu")
		(hatch edge 0.5)
		(priority 17)
		(connect_pads yes
			(clearance 0.2)
		)
		(min_thickness 0.25)
		(filled_areas_thickness no)
		(fill yes
			(thermal_gap 0.5)
			(thermal_bridge_width 0.5)
		)
		(polygon
			(pts
				(xy 83.626 89.25) (xy 84.776 89.25) (xy 84.776 91.25) (xy 83.626 91.25)
			)
		)
	)
	(zone
		(net 2)
		(net_name "GND")
		(layer "B.Cu")
		(hatch edge 0.5)
		(priority 21)
		(connect_pads yes
			(clearance 0.25)
		)
		(min_thickness 0.25)
		(filled_areas_thickness no)
		(fill yes
			(thermal_gap 0.5)
			(thermal_bridge_width 0.5)
		)
		(polygon
			(pts
				(xy 84.976 65.05) (xy 82.976 65.05) (xy 82.976 61.95) (xy 84.976 61.95)
			)
		)
	)
	(zone
		(net 23)
		(net_name "Net-(U4-SW)")
		(layer "B.Cu")
		(hatch edge 0.5)
		(priority 4)
		(connect_pads yes
			(clearance 0.125)
		)
		(min_thickness 0.25)
		(filled_areas_thickness no)
		(fill yes
			(thermal_gap 0.5)
			(thermal_bridge_width 0.5)
		)
		(polygon
			(pts
				(xy 84.339344 79.05) (xy 85.289344 79.05) (xy 86.189344 79.8) (xy 86.739344 79.8) (xy 86.739344 80.25)
				(xy 86.189344 80.25) (xy 85.789344 80.45) (xy 85.789344 81.15) (xy 86.05 81.5) (xy 86.05 82.325)
				(xy 86.05 82.7) (xy 85.9 82.825) (xy 84.725 82.825) (xy 84.725 82.525) (xy 85.375 82.525) (xy 85.55 82.35)
				(xy 85.55 81.9) (xy 85 81.6) (xy 85 81.2) (xy 84.339344 81.2)
			)
		)
	)
	(zone
		(net 5)
		(net_name "+12V")
		(layer "B.Cu")
		(hatch edge 0.5)
		(priority 23)
		(connect_pads yes
			(clearance 0.25)
		)
		(min_thickness 0.25)
		(filled_areas_thickness no)
		(fill yes
			(thermal_gap 0.5)
			(thermal_bridge_width 0.5)
		)
		(polygon
			(pts
				(xy 103.276 97.85) (xy 103.276 93.45) (xy 84.776 93.35) (xy 84.776 95.85) (xy 86.676 95.85) (xy 88.076 97.85)
			)
		)
	)
	(zone
		(net 1)
		(net_name "+3V3")
		(layer "B.Cu")
		(hatch edge 0.5)
		(priority 5)
		(connect_pads yes
			(clearance 0.25)
		)
		(min_thickness 0.25)
		(filled_areas_thickness no)
		(fill yes
			(thermal_gap 0.5)
			(thermal_bridge_width 0.5)
		)
		(polygon
			(pts
				(xy 82.05 76.825) (xy 83.425 76.825) (xy 83.425 81.225) (xy 83.15 81.575) (xy 83.15 82.525) (xy 82.05 82.525)
			)
		)
	)
	(zone
		(net 25)
		(net_name "+5V")
		(layer "B.Cu")
		(hatch edge 0.5)
		(priority 18)
		(connect_pads yes
			(clearance 0.25)
		)
		(min_thickness 0.25)
		(filled_areas_thickness no)
		(fill yes
			(thermal_gap 0.5)
			(thermal_bridge_width 0.5)
		)
		(polygon
			(pts
				(xy 81.876 85.3) (xy 83.776 85.3) (xy 83.776 87.35) (xy 83.376 87.7) (xy 83.376 88.1) (xy 82.876 88.6)
				(xy 82.876 90.8) (xy 81.876 90.8)
			)
		)
	)
	(zone
		(net 25)
		(net_name "+5V")
		(layer "B.Cu")
		(hatch edge 0.5)
		(priority 19)
		(connect_pads yes
			(clearance 0.2)
		)
		(min_thickness 0.25)
		(filled_areas_thickness no)
		(fill yes
			(thermal_gap 0.5)
			(thermal_bridge_width 0.5)
		)
		(polygon
			(pts
				(xy 90.9 88.75) (xy 90.9 90.9) (xy 94.85 90.9) (xy 95.45 89.95) (xy 98.7 89.95) (xy 98.7 89.1) (xy 95.95 89.1)
				(xy 95.6 88.75)
			)
		)
	)
	(zone
		(net 2)
		(net_name "GND")
		(layer "B.Cu")
		(hatch edge 0.5)
		(priority 7)
		(connect_pads yes
			(clearance 0.25)
		)
		(min_thickness 0.25)
		(filled_areas_thickness no)
		(fill yes
			(thermal_gap 0.5)
			(thermal_bridge_width 0.5)
		)
		(polygon
			(pts
				(xy 103.35 100.55) (xy 87.7 100.55) (xy 87.7 98) (xy 103.35 98)
			)
		)
	)
	(zone
		(net 2)
		(net_name "GND")
		(layer "B.Cu")
		(hatch edge 0.5)
		(priority 1)
		(connect_pads yes
			(clearance 0.25)
		)
		(min_thickness 0.25)
		(filled_areas_thickness no)
		(fill yes
			(thermal_gap 0.5)
			(thermal_bridge_width 0.5)
		)
		(polygon
			(pts
				(xy 103.951 111.675) (xy 80.951 111.675) (xy 81.076 75.85) (xy 104.076 75.85)
			)
		)
	)
	(zone
		(net 2)
		(net_name "GND")
		(layer "B.Cu")
		(hatch edge 0.5)
		(priority 20)
		(connect_pads yes
			(clearance 0.25)
		)
		(min_thickness 0.25)
		(filled_areas_thickness no)
		(fill yes
			(thermal_gap 0.5)
			(thermal_bridge_width 0.5)
		)
		(polygon
			(pts
				(xy 90.876 65.05) (xy 92.876 65.05) (xy 92.876 61.95) (xy 90.876 61.95)
			)
		)
	)
	(zone
		(net 2)
		(net_name "GND")
		(layer "B.Cu")
		(hatch edge 0.5)
		(priority 6)
		(connect_pads yes
			(clearance 0.25)
		)
		(min_thickness 0.25)
		(filled_areas_thickness no)
		(fill yes
			(thermal_gap 0.5)
			(thermal_bridge_width 0.5)
		)
		(polygon
			(pts
				(xy 96.95 93.4) (xy 96.95 90.2) (xy 88.15 90.2) (xy 88.15 93.4)
			)
		)
	)
	(zone
		(net 2)
		(net_name "GND")
		(layer "B.Cu")
		(hatch edge 0.5)
		(priority 13)
		(connect_pads yes
			(clearance 0.125)
		)
		(min_thickness 0.25)
		(filled_areas_thickness no)
		(fill yes
			(thermal_gap 0.5)
			(thermal_bridge_width 0.5)
		)
		(polygon
			(pts
				(xy 84.3 82.2) (xy 84.3 82.925) (xy 83.475 82.925) (xy 83.2 83.175) (xy 83.175 83.95) (xy 82 83.95)
				(xy 82 82.625) (xy 82.975 82.625) (xy 83.475 82.2)
			)
		)
	)
	(zone
		(net 21)
		(net_name "Net-(U3-SW)")
		(layer "B.Cu")
		(hatch edge 0.5)
		(priority 4)
		(connect_pads yes
			(clearance 0.125)
		)
		(min_thickness 0.125)
		(filled_areas_thickness no)
		(fill yes
			(thermal_gap 0.5)
			(thermal_bridge_width 0.5)
		)
		(polygon
			(pts
				(xy 84.334846 85.295769) (xy 85.284846 85.295769) (xy 86.184846 85.995769) (xy 86.734846 85.995769)
				(xy 86.734846 86.445769) (xy 86.184846 86.445769) (xy 85.784846 86.645769) (xy 85.784846 87.45)
				(xy 86.026 87.75) (xy 86.026 88.9) (xy 85.851 89.05) (xy 84.751 89.05) (xy 84.751 88.7) (xy 85.426 88.7)
				(xy 85.526 88.6) (xy 85.526 88.05) (xy 85.051 87.6) (xy 84.334846 87.6)
			)
		)
	)
	(zone
		(net 26)
		(net_name "Net-(D5-C)")
		(layer "B.Cu")
		(hatch edge 0.5)
		(priority 16)
		(connect_pads yes
			(clearance 0.25)
		)
		(min_thickness 0.25)
		(filled_areas_thickness no)
		(fill yes
			(thermal_gap 0.5)
			(thermal_bridge_width 0.5)
		)
		(polygon
			(pts
				(xy 81.976 96.05) (xy 87.776 96.05) (xy 87.776 103.25) (xy 85.676 103.25) (xy 85.676 101.05) (xy 81.976 99.25)
			)
		)
	)
	(zone
		(net 6)
		(net_name "VBUS")
		(layers "B.Cu" "In2.Cu")
		(hatch edge 0.5)
		(priority 11)
		(connect_pads yes
			(clearance 0.125)
		)
		(min_thickness 0.25)
		(filled_areas_thickness no)
		(fill yes
			(thermal_gap 0.5)
			(thermal_bridge_width 0.5)
		)
		(polygon
			(pts
				(xy 85.1 65.3) (xy 85.1 62.1) (xy 90.8 62.1) (xy 90.8 65.1) (xy 91.3 65.6) (xy 91.3 71.8) (xy 89.25 71.85)
				(xy 89.25 65.65) (xy 89.9 65.1) (xy 89.9 63.95) (xy 89.826 63.875) (xy 86.2 63.875) (xy 85.9 64.1)
				(xy 85.9 65.3)
			)
		)
	)
	(zone
		(net 0)
		(net_name "")
		(layers "B.Cu" "Edge.Cuts")
		(hatch full 0.5)
		(connect_pads
			(clearance 0)
		)
		(min_thickness 0.25)
		(filled_areas_thickness no)
		(keepout
			(tracks allowed)
			(vias allowed)
			(pads not_allowed)
			(copperpour allowed)
			(footprints allowed)
		)
		(placement
			(enabled no)
			(sheetname "")
		)
		(fill
			(thermal_gap 0.5)
			(thermal_bridge_width 0.5)
		)
		(polygon
			(pts
				(xy 80.6 78.4) (xy 80.6 70.9) (xy 103.8 70.9) (xy 103.8 78.4)
			)
		)
	)
	(zone
		(net 2)
		(net_name "GND")
		(layer "In1.Cu")
		(hatch edge 0.5)
		(priority 12)
		(connect_pads yes
			(clearance 0.2)
		)
		(min_thickness 0.25)
		(filled_areas_thickness no)
		(fill yes
			(thermal_gap 0.5)
			(thermal_bridge_width 0.5)
		)
		(polygon
			(pts
				(xy 94 58) (xy 94 70) (xy 104 70) (xy 103.975 111.45) (xy 80.975 111.45) (xy 81 58)
			)
		)
	)
	(zone
		(net 25)
		(net_name "+5V")
		(layer "In1.Cu")
		(hatch edge 0.5)
		(priority 25)
		(connect_pads yes
			(clearance 0.25)
		)
		(min_thickness 0.25)
		(filled_areas_thickness no)
		(fill yes
			(thermal_gap 0.5)
			(thermal_bridge_width 0.5)
		)
		(polygon
			(pts
				(xy 81.876 88.85) (xy 92.276 88.85) (xy 92.276 90.85) (xy 81.876 90.85)
			)
		)
	)
	(zone
		(net 5)
		(net_name "+12V")
		(layer "In2.Cu")
		(hatch edge 0.5)
		(priority 14)
		(connect_pads yes
			(clearance 0.25)
		)
		(min_thickness 0.25)
		(filled_areas_thickness no)
		(fill yes
			(thermal_gap 0.5)
			(thermal_bridge_width 0.5)
		)
		(polygon
			(pts
				(xy 82.076 83.95) (xy 86.576 83.95) (xy 86.576 89.2) (xy 89.076 91.7) (xy 102.126 91.7) (xy 102.126 97.75)
				(xy 85.576 97.75) (xy 82.076 97.75) (xy 82.076 89.15) (xy 82.076 88.05)
			)
		)
	)
	(zone
		(net 1)
		(net_name "+3V3")
		(layer "In2.Cu")
		(hatch edge 0.5)
		(priority 6)
		(connect_pads yes
			(clearance 0.2)
		)
		(min_thickness 0.25)
		(filled_areas_thickness no)
		(fill yes
			(thermal_gap 0.5)
			(thermal_bridge_width 0.5)
		)
		(polygon
			(pts
				(xy 80 68.5) (xy 105.5 68.5) (xy 105.5 88) (xy 80 88)
			)
		)
	)
)
